(kicad_sch
	(version 20250114)
	(generator "eeschema")
	(generator_version "9.0")
	(paper "A3")
	(title_block
		(title "Artix - Datacenter Secure Control Module (DC-SCM)")
		(date "2024-11-06")
		(rev "1.1.3")
	)
	(text "RoT module connector"
		(exclude_from_sim no)
		(at 207.01 97.155 0)
		(effects
			(font
				(size 2.9972 2.9972)
				(thickness 0.5994)
				(bold yes)
			)
			(justify left bottom)
		)
	)
	(text "One or typically two flash devices used to contain the BMC firmware image"
		(exclude_from_sim no)
		(at 41.91 162.56 0)
		(effects
			(font
				(size 1.27 1.27)
			)
			(justify left bottom)
		)
	)
	(text "TPM connector"
		(exclude_from_sim no)
		(at 299.085 110.49 0)
		(effects
			(font
				(size 2.9972 2.9972)
				(thickness 0.5994)
				(bold yes)
			)
			(justify left bottom)
		)
	)
	(text "BMC flash"
		(exclude_from_sim no)
		(at 41.275 156.845 0)
		(effects
			(font
				(size 2.9972 2.9972)
				(thickness 0.5994)
				(bold yes)
			)
			(justify left bottom)
		)
	)
	(text "BIOS flash"
		(exclude_from_sim no)
		(at 36.195 31.75 0)
		(effects
			(font
				(size 2.9972 2.9972)
				(thickness 0.5994)
				(bold yes)
			)
			(justify left bottom)
		)
	)
	(text "One or typically two flash devices used to contain the BIOS firmware image"
		(exclude_from_sim no)
		(at 37.465 37.465 0)
		(effects
			(font
				(size 1.27 1.27)
			)
			(justify left bottom)
		)
	)
	(text "Pinout for AES-PMOD-TPM20-SLB9670-G"
		(exclude_from_sim no)
		(at 328.295 145.415 0)
		(effects
			(font
				(size 1.27 1.27)
			)
			(justify left bottom)
		)
	)
	(text "preliminary\n"
		(exclude_from_sim no)
		(at 229.235 177.8 0)
		(effects
			(font
				(size 1.27 1.27)
			)
			(justify left bottom)
		)
	)
	(junction
		(at 73.66 50.8)
		(diameter 0)
		(color 0 0 0 0)
	)
	(junction
		(at 58.42 222.25)
		(diameter 0)
		(color 0 0 0 0)
	)
	(junction
		(at 66.04 187.96)
		(diameter 0)
		(color 0 0 0 0)
	)
	(junction
		(at 58.42 109.22)
		(diameter 0)
		(color 0 0 0 0)
	)
	(junction
		(at 73.66 114.3)
		(diameter 0)
		(color 0 0 0 0)
	)
	(junction
		(at 113.03 231.14)
		(diameter 0)
		(color 0 0 0 0)
	)
	(junction
		(at 73.66 190.5)
		(diameter 0)
		(color 0 0 0 0)
	)
	(junction
		(at 233.68 168.91)
		(diameter 0)
		(color 0 0 0 0)
	)
	(junction
		(at 66.04 171.45)
		(diameter 0)
		(color 0 0 0 0)
	)
	(junction
		(at 113.03 193.04)
		(diameter 0)
		(color 0 0 0 0)
	)
	(junction
		(at 43.18 62.23)
		(diameter 0)
		(color 0 0 0 0)
	)
	(junction
		(at 81.28 72.39)
		(diameter 0)
		(color 0 0 0 0)
	)
	(junction
		(at 50.8 171.45)
		(diameter 0)
		(color 0 0 0 0)
	)
	(junction
		(at 43.18 222.25)
		(diameter 0)
		(color 0 0 0 0)
	)
	(junction
		(at 58.42 95.25)
		(diameter 0)
		(color 0 0 0 0)
	)
	(junction
		(at 50.8 231.14)
		(diameter 0)
		(color 0 0 0 0)
	)
	(junction
		(at 58.42 236.22)
		(diameter 0)
		(color 0 0 0 0)
	)
	(junction
		(at 43.18 233.68)
		(diameter 0)
		(color 0 0 0 0)
	)
	(junction
		(at 66.04 95.25)
		(diameter 0)
		(color 0 0 0 0)
	)
	(junction
		(at 73.66 69.85)
		(diameter 0)
		(color 0 0 0 0)
	)
	(junction
		(at 50.8 180.34)
		(diameter 0)
		(color 0 0 0 0)
	)
	(junction
		(at 58.42 50.8)
		(diameter 0)
		(color 0 0 0 0)
	)
	(junction
		(at 66.04 111.76)
		(diameter 0)
		(color 0 0 0 0)
	)
	(junction
		(at 58.42 185.42)
		(diameter 0)
		(color 0 0 0 0)
	)
	(junction
		(at 73.66 171.45)
		(diameter 0)
		(color 0 0 0 0)
	)
	(junction
		(at 66.04 50.8)
		(diameter 0)
		(color 0 0 0 0)
	)
	(junction
		(at 50.8 222.25)
		(diameter 0)
		(color 0 0 0 0)
	)
	(junction
		(at 50.8 104.14)
		(diameter 0)
		(color 0 0 0 0)
	)
	(junction
		(at 66.04 238.76)
		(diameter 0)
		(color 0 0 0 0)
	)
	(junction
		(at 73.66 95.25)
		(diameter 0)
		(color 0 0 0 0)
	)
	(junction
		(at 113.03 72.39)
		(diameter 0)
		(color 0 0 0 0)
	)
	(junction
		(at 58.42 171.45)
		(diameter 0)
		(color 0 0 0 0)
	)
	(junction
		(at 66.04 67.31)
		(diameter 0)
		(color 0 0 0 0)
	)
	(junction
		(at 43.18 50.8)
		(diameter 0)
		(color 0 0 0 0)
	)
	(junction
		(at 50.8 95.25)
		(diameter 0)
		(color 0 0 0 0)
	)
	(junction
		(at 113.03 104.14)
		(diameter 0)
		(color 0 0 0 0)
	)
	(junction
		(at 220.98 171.45)
		(diameter 0)
		(color 0 0 0 0)
	)
	(junction
		(at 43.18 182.88)
		(diameter 0)
		(color 0 0 0 0)
	)
	(junction
		(at 43.18 106.68)
		(diameter 0)
		(color 0 0 0 0)
	)
	(junction
		(at 58.42 64.77)
		(diameter 0)
		(color 0 0 0 0)
	)
	(junction
		(at 113.03 59.69)
		(diameter 0)
		(color 0 0 0 0)
	)
	(junction
		(at 113.03 116.84)
		(diameter 0)
		(color 0 0 0 0)
	)
	(junction
		(at 50.8 59.69)
		(diameter 0)
		(color 0 0 0 0)
	)
	(junction
		(at 73.66 222.25)
		(diameter 0)
		(color 0 0 0 0)
	)
	(junction
		(at 81.28 193.04)
		(diameter 0)
		(color 0 0 0 0)
	)
	(junction
		(at 73.66 241.3)
		(diameter 0)
		(color 0 0 0 0)
	)
	(junction
		(at 81.28 116.84)
		(diameter 0)
		(color 0 0 0 0)
	)
	(junction
		(at 113.03 180.34)
		(diameter 0)
		(color 0 0 0 0)
	)
	(junction
		(at 66.04 222.25)
		(diameter 0)
		(color 0 0 0 0)
	)
	(junction
		(at 43.18 95.25)
		(diameter 0)
		(color 0 0 0 0)
	)
	(junction
		(at 113.03 243.84)
		(diameter 0)
		(color 0 0 0 0)
	)
	(junction
		(at 50.8 50.8)
		(diameter 0)
		(color 0 0 0 0)
	)
	(junction
		(at 81.28 243.84)
		(diameter 0)
		(color 0 0 0 0)
	)
	(junction
		(at 43.18 171.45)
		(diameter 0)
		(color 0 0 0 0)
	)
	(no_connect
		(at 220.98 185.42)
	)
	(wire
		(pts
			(xy 222.25 161.29) (xy 209.55 161.29)
		)
		(stroke
			(width 0)
			(type default)
		)
	)
	(wire
		(pts
			(xy 43.18 171.45) (xy 50.8 171.45)
		)
		(stroke
			(width 0)
			(type default)
		)
	)
	(wire
		(pts
			(xy 81.28 57.15) (xy 81.28 72.39)
		)
		(stroke
			(width 0)
			(type default)
		)
	)
	(wire
		(pts
			(xy 66.04 187.96) (xy 92.71 187.96)
		)
		(stroke
			(width 0)
			(type default)
		)
	)
	(wire
		(pts
			(xy 50.8 104.14) (xy 92.71 104.14)
		)
		(stroke
			(width 0)
			(type default)
		)
	)
	(wire
		(pts
			(xy 66.04 222.25) (xy 66.04 223.52)
		)
		(stroke
			(width 0)
			(type default)
		)
	)
	(wire
		(pts
			(xy 66.04 57.15) (xy 66.04 67.31)
		)
		(stroke
			(width 0)
			(type default)
		)
	)
	(wire
		(pts
			(xy 66.04 222.25) (xy 73.66 222.25)
		)
		(stroke
			(width 0)
			(type default)
		)
	)
	(wire
		(pts
			(xy 50.8 222.25) (xy 58.42 222.25)
		)
		(stroke
			(width 0)
			(type default)
		)
	)
	(wire
		(pts
			(xy 50.8 95.25) (xy 58.42 95.25)
		)
		(stroke
			(width 0)
			(type default)
		)
	)
	(wire
		(pts
			(xy 50.8 222.25) (xy 50.8 223.52)
		)
		(stroke
			(width 0)
			(type default)
		)
	)
	(wire
		(pts
			(xy 233.68 125.73) (xy 246.38 125.73)
		)
		(stroke
			(width 0)
			(type default)
		)
	)
	(wire
		(pts
			(xy 66.04 95.25) (xy 66.04 96.52)
		)
		(stroke
			(width 0)
			(type default)
		)
	)
	(wire
		(pts
			(xy 73.66 114.3) (xy 92.71 114.3)
		)
		(stroke
			(width 0)
			(type default)
		)
	)
	(wire
		(pts
			(xy 222.25 133.35) (xy 209.55 133.35)
		)
		(stroke
			(width 0)
			(type default)
		)
	)
	(wire
		(pts
			(xy 222.25 138.43) (xy 209.55 138.43)
		)
		(stroke
			(width 0)
			(type default)
		)
	)
	(wire
		(pts
			(xy 73.66 222.25) (xy 81.28 222.25)
		)
		(stroke
			(width 0)
			(type default)
		)
	)
	(wire
		(pts
			(xy 50.8 59.69) (xy 92.71 59.69)
		)
		(stroke
			(width 0)
			(type default)
		)
	)
	(wire
		(pts
			(xy 222.25 166.37) (xy 209.55 166.37)
		)
		(stroke
			(width 0)
			(type default)
		)
	)
	(wire
		(pts
			(xy 58.42 171.45) (xy 66.04 171.45)
		)
		(stroke
			(width 0)
			(type default)
		)
	)
	(wire
		(pts
			(xy 111.76 59.69) (xy 113.03 59.69)
		)
		(stroke
			(width 0)
			(type default)
		)
	)
	(wire
		(pts
			(xy 233.68 130.81) (xy 246.38 130.81)
		)
		(stroke
			(width 0)
			(type default)
		)
	)
	(wire
		(pts
			(xy 113.03 63.5) (xy 113.03 59.69)
		)
		(stroke
			(width 0)
			(type default)
		)
	)
	(wire
		(pts
			(xy 58.42 95.25) (xy 66.04 95.25)
		)
		(stroke
			(width 0)
			(type default)
		)
	)
	(wire
		(pts
			(xy 233.68 146.05) (xy 246.38 146.05)
		)
		(stroke
			(width 0)
			(type default)
		)
	)
	(wire
		(pts
			(xy 113.03 176.53) (xy 113.03 180.34)
		)
		(stroke
			(width 0)
			(type default)
		)
	)
	(wire
		(pts
			(xy 66.04 67.31) (xy 92.71 67.31)
		)
		(stroke
			(width 0)
			(type default)
		)
	)
	(wire
		(pts
			(xy 43.18 101.6) (xy 43.18 106.68)
		)
		(stroke
			(width 0)
			(type default)
		)
	)
	(wire
		(pts
			(xy 40.64 182.88) (xy 43.18 182.88)
		)
		(stroke
			(width 0)
			(type default)
		)
	)
	(wire
		(pts
			(xy 246.38 153.67) (xy 233.68 153.67)
		)
		(stroke
			(width 0)
			(type default)
		)
	)
	(wire
		(pts
			(xy 222.25 120.65) (xy 209.55 120.65)
		)
		(stroke
			(width 0)
			(type default)
		)
	)
	(wire
		(pts
			(xy 40.64 104.14) (xy 50.8 104.14)
		)
		(stroke
			(width 0)
			(type default)
		)
	)
	(wire
		(pts
			(xy 73.66 241.3) (xy 92.71 241.3)
		)
		(stroke
			(width 0)
			(type default)
		)
	)
	(wire
		(pts
			(xy 222.25 135.89) (xy 209.55 135.89)
		)
		(stroke
			(width 0)
			(type default)
		)
	)
	(wire
		(pts
			(xy 322.58 140.97) (xy 335.28 140.97)
		)
		(stroke
			(width 0)
			(type default)
		)
	)
	(wire
		(pts
			(xy 81.28 171.45) (xy 81.28 172.72)
		)
		(stroke
			(width 0)
			(type default)
		)
	)
	(wire
		(pts
			(xy 113.03 243.84) (xy 113.03 245.11)
		)
		(stroke
			(width 0)
			(type default)
		)
	)
	(wire
		(pts
			(xy 50.8 228.6) (xy 50.8 231.14)
		)
		(stroke
			(width 0)
			(type default)
		)
	)
	(wire
		(pts
			(xy 222.25 163.83) (xy 209.55 163.83)
		)
		(stroke
			(width 0)
			(type default)
		)
	)
	(wire
		(pts
			(xy 222.25 110.49) (xy 209.55 110.49)
		)
		(stroke
			(width 0)
			(type default)
		)
	)
	(wire
		(pts
			(xy 220.98 168.91) (xy 220.98 171.45)
		)
		(stroke
			(width 0)
			(type default)
		)
	)
	(wire
		(pts
			(xy 58.42 50.8) (xy 66.04 50.8)
		)
		(stroke
			(width 0)
			(type default)
		)
	)
	(wire
		(pts
			(xy 43.18 171.45) (xy 43.18 172.72)
		)
		(stroke
			(width 0)
			(type default)
		)
	)
	(wire
		(pts
			(xy 58.42 109.22) (xy 92.71 109.22)
		)
		(stroke
			(width 0)
			(type default)
		)
	)
	(wire
		(pts
			(xy 246.38 158.75) (xy 233.68 158.75)
		)
		(stroke
			(width 0)
			(type default)
		)
	)
	(wire
		(pts
			(xy 66.04 238.76) (xy 92.71 238.76)
		)
		(stroke
			(width 0)
			(type default)
		)
	)
	(wire
		(pts
			(xy 66.04 95.25) (xy 73.66 95.25)
		)
		(stroke
			(width 0)
			(type default)
		)
	)
	(wire
		(pts
			(xy 40.64 50.8) (xy 43.18 50.8)
		)
		(stroke
			(width 0)
			(type default)
		)
	)
	(wire
		(pts
			(xy 40.64 95.25) (xy 43.18 95.25)
		)
		(stroke
			(width 0)
			(type default)
		)
	)
	(wire
		(pts
			(xy 111.76 180.34) (xy 113.03 180.34)
		)
		(stroke
			(width 0)
			(type default)
		)
	)
	(wire
		(pts
			(xy 43.18 50.8) (xy 50.8 50.8)
		)
		(stroke
			(width 0)
			(type default)
		)
	)
	(wire
		(pts
			(xy 73.66 101.6) (xy 73.66 114.3)
		)
		(stroke
			(width 0)
			(type default)
		)
	)
	(wire
		(pts
			(xy 73.66 171.45) (xy 73.66 172.72)
		)
		(stroke
			(width 0)
			(type default)
		)
	)
	(wire
		(pts
			(xy 40.64 114.3) (xy 73.66 114.3)
		)
		(stroke
			(width 0)
			(type default)
		)
	)
	(wire
		(pts
			(xy 58.42 171.45) (xy 58.42 172.72)
		)
		(stroke
			(width 0)
			(type default)
		)
	)
	(wire
		(pts
			(xy 246.38 118.11) (xy 233.68 118.11)
		)
		(stroke
			(width 0)
			(type default)
		)
	)
	(wire
		(pts
			(xy 113.03 72.39) (xy 113.03 73.66)
		)
		(stroke
			(width 0)
			(type default)
		)
	)
	(wire
		(pts
			(xy 233.68 115.57) (xy 246.38 115.57)
		)
		(stroke
			(width 0)
			(type default)
		)
	)
	(wire
		(pts
			(xy 81.28 177.8) (xy 81.28 193.04)
		)
		(stroke
			(width 0)
			(type default)
		)
	)
	(wire
		(pts
			(xy 113.03 193.04) (xy 111.76 193.04)
		)
		(stroke
			(width 0)
			(type default)
		)
	)
	(wire
		(pts
			(xy 220.98 171.45) (xy 222.25 171.45)
		)
		(stroke
			(width 0)
			(type default)
		)
	)
	(wire
		(pts
			(xy 66.04 171.45) (xy 66.04 172.72)
		)
		(stroke
			(width 0)
			(type default)
		)
	)
	(wire
		(pts
			(xy 58.42 50.8) (xy 58.42 52.07)
		)
		(stroke
			(width 0)
			(type default)
		)
	)
	(wire
		(pts
			(xy 50.8 171.45) (xy 58.42 171.45)
		)
		(stroke
			(width 0)
			(type default)
		)
	)
	(wire
		(pts
			(xy 43.18 222.25) (xy 43.18 223.52)
		)
		(stroke
			(width 0)
			(type default)
		)
	)
	(wire
		(pts
			(xy 113.03 113.03) (xy 113.03 116.84)
		)
		(stroke
			(width 0)
			(type default)
		)
	)
	(wire
		(pts
			(xy 43.18 233.68) (xy 92.71 233.68)
		)
		(stroke
			(width 0)
			(type default)
		)
	)
	(wire
		(pts
			(xy 40.64 231.14) (xy 50.8 231.14)
		)
		(stroke
			(width 0)
			(type default)
		)
	)
	(wire
		(pts
			(xy 66.04 111.76) (xy 92.71 111.76)
		)
		(stroke
			(width 0)
			(type default)
		)
	)
	(wire
		(pts
			(xy 58.42 236.22) (xy 92.71 236.22)
		)
		(stroke
			(width 0)
			(type default)
		)
	)
	(wire
		(pts
			(xy 81.28 101.6) (xy 81.28 116.84)
		)
		(stroke
			(width 0)
			(type default)
		)
	)
	(wire
		(pts
			(xy 73.66 222.25) (xy 73.66 223.52)
		)
		(stroke
			(width 0)
			(type default)
		)
	)
	(wire
		(pts
			(xy 43.18 57.15) (xy 43.18 62.23)
		)
		(stroke
			(width 0)
			(type default)
		)
	)
	(wire
		(pts
			(xy 222.25 151.13) (xy 209.55 151.13)
		)
		(stroke
			(width 0)
			(type default)
		)
	)
	(wire
		(pts
			(xy 312.42 140.97) (xy 295.91 140.97)
		)
		(stroke
			(width 0)
			(type default)
		)
	)
	(wire
		(pts
			(xy 81.28 243.84) (xy 92.71 243.84)
		)
		(stroke
			(width 0)
			(type default)
		)
	)
	(wire
		(pts
			(xy 115.57 227.33) (xy 113.03 227.33)
		)
		(stroke
			(width 0)
			(type default)
		)
	)
	(wire
		(pts
			(xy 222.25 158.75) (xy 209.55 158.75)
		)
		(stroke
			(width 0)
			(type default)
		)
	)
	(wire
		(pts
			(xy 81.28 95.25) (xy 81.28 96.52)
		)
		(stroke
			(width 0)
			(type default)
		)
	)
	(wire
		(pts
			(xy 233.68 143.51) (xy 246.38 143.51)
		)
		(stroke
			(width 0)
			(type default)
		)
	)
	(wire
		(pts
			(xy 233.68 168.91) (xy 248.92 168.91)
		)
		(stroke
			(width 0)
			(type default)
		)
	)
	(wire
		(pts
			(xy 113.03 240.03) (xy 113.03 243.84)
		)
		(stroke
			(width 0)
			(type default)
		)
	)
	(wire
		(pts
			(xy 66.04 101.6) (xy 66.04 111.76)
		)
		(stroke
			(width 0)
			(type default)
		)
	)
	(wire
		(pts
			(xy 40.64 190.5) (xy 73.66 190.5)
		)
		(stroke
			(width 0)
			(type default)
		)
	)
	(wire
		(pts
			(xy 220.98 168.91) (xy 222.25 168.91)
		)
		(stroke
			(width 0)
			(type default)
		)
	)
	(wire
		(pts
			(xy 73.66 95.25) (xy 81.28 95.25)
		)
		(stroke
			(width 0)
			(type default)
		)
	)
	(wire
		(pts
			(xy 73.66 95.25) (xy 73.66 96.52)
		)
		(stroke
			(width 0)
			(type default)
		)
	)
	(wire
		(pts
			(xy 50.8 177.8) (xy 50.8 180.34)
		)
		(stroke
			(width 0)
			(type default)
		)
	)
	(wire
		(pts
			(xy 50.8 57.15) (xy 50.8 59.69)
		)
		(stroke
			(width 0)
			(type default)
		)
	)
	(wire
		(pts
			(xy 58.42 57.15) (xy 58.42 64.77)
		)
		(stroke
			(width 0)
			(type default)
		)
	)
	(wire
		(pts
			(xy 222.25 115.57) (xy 209.55 115.57)
		)
		(stroke
			(width 0)
			(type default)
		)
	)
	(wire
		(pts
			(xy 246.38 120.65) (xy 233.68 120.65)
		)
		(stroke
			(width 0)
			(type default)
		)
	)
	(wire
		(pts
			(xy 113.03 100.33) (xy 113.03 104.14)
		)
		(stroke
			(width 0)
			(type default)
		)
	)
	(wire
		(pts
			(xy 40.64 243.84) (xy 81.28 243.84)
		)
		(stroke
			(width 0)
			(type default)
		)
	)
	(wire
		(pts
			(xy 40.64 233.68) (xy 43.18 233.68)
		)
		(stroke
			(width 0)
			(type default)
		)
	)
	(wire
		(pts
			(xy 58.42 222.25) (xy 66.04 222.25)
		)
		(stroke
			(width 0)
			(type default)
		)
	)
	(wire
		(pts
			(xy 222.25 130.81) (xy 209.55 130.81)
		)
		(stroke
			(width 0)
			(type default)
		)
	)
	(wire
		(pts
			(xy 113.03 243.84) (xy 111.76 243.84)
		)
		(stroke
			(width 0)
			(type default)
		)
	)
	(wire
		(pts
			(xy 73.66 171.45) (xy 81.28 171.45)
		)
		(stroke
			(width 0)
			(type default)
		)
	)
	(wire
		(pts
			(xy 73.66 50.8) (xy 81.28 50.8)
		)
		(stroke
			(width 0)
			(type default)
		)
	)
	(wire
		(pts
			(xy 50.8 50.8) (xy 50.8 52.07)
		)
		(stroke
			(width 0)
			(type default)
		)
	)
	(wire
		(pts
			(xy 40.64 116.84) (xy 81.28 116.84)
		)
		(stroke
			(width 0)
			(type default)
		)
	)
	(wire
		(pts
			(xy 113.03 68.58) (xy 113.03 72.39)
		)
		(stroke
			(width 0)
			(type default)
		)
	)
	(wire
		(pts
			(xy 233.68 148.59) (xy 246.38 148.59)
		)
		(stroke
			(width 0)
			(type default)
		)
	)
	(wire
		(pts
			(xy 43.18 177.8) (xy 43.18 182.88)
		)
		(stroke
			(width 0)
			(type default)
		)
	)
	(wire
		(pts
			(xy 43.18 62.23) (xy 92.71 62.23)
		)
		(stroke
			(width 0)
			(type default)
		)
	)
	(wire
		(pts
			(xy 233.68 140.97) (xy 246.38 140.97)
		)
		(stroke
			(width 0)
			(type default)
		)
	)
	(wire
		(pts
			(xy 115.57 100.33) (xy 113.03 100.33)
		)
		(stroke
			(width 0)
			(type default)
		)
	)
	(wire
		(pts
			(xy 335.28 140.97) (xy 335.28 127)
		)
		(stroke
			(width 0)
			(type default)
		)
	)
	(wire
		(pts
			(xy 40.64 111.76) (xy 66.04 111.76)
		)
		(stroke
			(width 0)
			(type default)
		)
	)
	(wire
		(pts
			(xy 40.64 72.39) (xy 81.28 72.39)
		)
		(stroke
			(width 0)
			(type default)
		)
	)
	(wire
		(pts
			(xy 66.04 50.8) (xy 66.04 52.07)
		)
		(stroke
			(width 0)
			(type default)
		)
	)
	(wire
		(pts
			(xy 113.03 184.15) (xy 113.03 180.34)
		)
		(stroke
			(width 0)
			(type default)
		)
	)
	(wire
		(pts
			(xy 81.28 116.84) (xy 92.71 116.84)
		)
		(stroke
			(width 0)
			(type default)
		)
	)
	(wire
		(pts
			(xy 222.25 128.27) (xy 209.55 128.27)
		)
		(stroke
			(width 0)
			(type default)
		)
	)
	(wire
		(pts
			(xy 233.68 135.89) (xy 246.38 135.89)
		)
		(stroke
			(width 0)
			(type default)
		)
	)
	(wire
		(pts
			(xy 50.8 231.14) (xy 92.71 231.14)
		)
		(stroke
			(width 0)
			(type default)
		)
	)
	(wire
		(pts
			(xy 40.64 222.25) (xy 43.18 222.25)
		)
		(stroke
			(width 0)
			(type default)
		)
	)
	(wire
		(pts
			(xy 113.03 107.95) (xy 113.03 104.14)
		)
		(stroke
			(width 0)
			(type default)
		)
	)
	(wire
		(pts
			(xy 113.03 189.23) (xy 113.03 193.04)
		)
		(stroke
			(width 0)
			(type default)
		)
	)
	(wire
		(pts
			(xy 222.25 143.51) (xy 209.55 143.51)
		)
		(stroke
			(width 0)
			(type default)
		)
	)
	(wire
		(pts
			(xy 40.64 241.3) (xy 73.66 241.3)
		)
		(stroke
			(width 0)
			(type default)
		)
	)
	(wire
		(pts
			(xy 40.64 187.96) (xy 66.04 187.96)
		)
		(stroke
			(width 0)
			(type default)
		)
	)
	(wire
		(pts
			(xy 308.61 138.43) (xy 308.61 144.78)
		)
		(stroke
			(width 0)
			(type default)
		)
	)
	(wire
		(pts
			(xy 66.04 228.6) (xy 66.04 238.76)
		)
		(stroke
			(width 0)
			(type default)
		)
	)
	(wire
		(pts
			(xy 43.18 228.6) (xy 43.18 233.68)
		)
		(stroke
			(width 0)
			(type default)
		)
	)
	(wire
		(pts
			(xy 58.42 185.42) (xy 92.71 185.42)
		)
		(stroke
			(width 0)
			(type default)
		)
	)
	(wire
		(pts
			(xy 58.42 101.6) (xy 58.42 109.22)
		)
		(stroke
			(width 0)
			(type default)
		)
	)
	(wire
		(pts
			(xy 40.64 59.69) (xy 50.8 59.69)
		)
		(stroke
			(width 0)
			(type default)
		)
	)
	(wire
		(pts
			(xy 222.25 156.21) (xy 209.55 156.21)
		)
		(stroke
			(width 0)
			(type default)
		)
	)
	(wire
		(pts
			(xy 50.8 180.34) (xy 92.71 180.34)
		)
		(stroke
			(width 0)
			(type default)
		)
	)
	(wire
		(pts
			(xy 43.18 106.68) (xy 92.71 106.68)
		)
		(stroke
			(width 0)
			(type default)
		)
	)
	(wire
		(pts
			(xy 113.03 227.33) (xy 113.03 231.14)
		)
		(stroke
			(width 0)
			(type default)
		)
	)
	(wire
		(pts
			(xy 111.76 104.14) (xy 113.03 104.14)
		)
		(stroke
			(width 0)
			(type default)
		)
	)
	(wire
		(pts
			(xy 233.68 138.43) (xy 246.38 138.43)
		)
		(stroke
			(width 0)
			(type default)
		)
	)
	(wire
		(pts
			(xy 113.03 55.88) (xy 113.03 59.69)
		)
		(stroke
			(width 0)
			(type default)
		)
	)
	(wire
		(pts
			(xy 113.03 72.39) (xy 111.76 72.39)
		)
		(stroke
			(width 0)
			(type default)
		)
	)
	(wire
		(pts
			(xy 73.66 177.8) (xy 73.66 190.5)
		)
		(stroke
			(width 0)
			(type default)
		)
	)
	(wire
		(pts
			(xy 312.42 138.43) (xy 308.61 138.43)
		)
		(stroke
			(width 0)
			(type default)
		)
	)
	(wire
		(pts
			(xy 209.55 153.67) (xy 222.25 153.67)
		)
		(stroke
			(width 0)
			(type default)
		)
	)
	(wire
		(pts
			(xy 43.18 95.25) (xy 50.8 95.25)
		)
		(stroke
			(width 0)
			(type default)
		)
	)
	(wire
		(pts
			(xy 246.38 123.19) (xy 233.68 123.19)
		)
		(stroke
			(width 0)
			(type default)
		)
	)
	(wire
		(pts
			(xy 66.04 50.8) (xy 73.66 50.8)
		)
		(stroke
			(width 0)
			(type default)
		)
	)
	(wire
		(pts
			(xy 43.18 182.88) (xy 92.71 182.88)
		)
		(stroke
			(width 0)
			(type default)
		)
	)
	(wire
		(pts
			(xy 73.66 69.85) (xy 92.71 69.85)
		)
		(stroke
			(width 0)
			(type default)
		)
	)
	(wire
		(pts
			(xy 50.8 171.45) (xy 50.8 172.72)
		)
		(stroke
			(width 0)
			(type default)
		)
	)
	(wire
		(pts
			(xy 222.25 118.11) (xy 209.55 118.11)
		)
		(stroke
			(width 0)
			(type default)
		)
	)
	(wire
		(pts
			(xy 40.64 62.23) (xy 43.18 62.23)
		)
		(stroke
			(width 0)
			(type default)
		)
	)
	(wire
		(pts
			(xy 73.66 50.8) (xy 73.66 52.07)
		)
		(stroke
			(width 0)
			(type default)
		)
	)
	(wire
		(pts
			(xy 233.68 151.13) (xy 246.38 151.13)
		)
		(stroke
			(width 0)
			(type default)
		)
	)
	(wire
		(pts
			(xy 322.58 138.43) (xy 325.12 138.43)
		)
		(stroke
			(width 0)
			(type default)
		)
	)
	(wire
		(pts
			(xy 233.68 166.37) (xy 246.38 166.37)
		)
		(stroke
			(width 0)
			(type default)
		)
	)
	(wire
		(pts
			(xy 246.38 156.21) (xy 233.68 156.21)
		)
		(stroke
			(width 0)
			(type default)
		)
	)
	(wire
		(pts
			(xy 113.03 116.84) (xy 111.76 116.84)
		)
		(stroke
			(width 0)
			(type default)
		)
	)
	(wire
		(pts
			(xy 73.66 228.6) (xy 73.66 241.3)
		)
		(stroke
			(width 0)
			(type default)
		)
	)
	(wire
		(pts
			(xy 233.68 163.83) (xy 246.38 163.83)
		)
		(stroke
			(width 0)
			(type default)
		)
	)
	(wire
		(pts
			(xy 81.28 228.6) (xy 81.28 243.84)
		)
		(stroke
			(width 0)
			(type default)
		)
	)
	(wire
		(pts
			(xy 81.28 193.04) (xy 92.71 193.04)
		)
		(stroke
			(width 0)
			(type default)
		)
	)
	(wire
		(pts
			(xy 73.66 57.15) (xy 73.66 69.85)
		)
		(stroke
			(width 0)
			(type default)
		)
	)
	(wire
		(pts
			(xy 66.04 177.8) (xy 66.04 187.96)
		)
		(stroke
			(width 0)
			(type default)
		)
	)
	(wire
		(pts
			(xy 233.68 171.45) (xy 233.68 168.91)
		)
		(stroke
			(width 0)
			(type default)
		)
	)
	(wire
		(pts
			(xy 50.8 50.8) (xy 58.42 50.8)
		)
		(stroke
			(width 0)
			(type default)
		)
	)
	(wire
		(pts
			(xy 222.25 113.03) (xy 209.55 113.03)
		)
		(stroke
			(width 0)
			(type default)
		)
	)
	(wire
		(pts
			(xy 40.64 67.31) (xy 66.04 67.31)
		)
		(stroke
			(width 0)
			(type default)
		)
	)
	(wire
		(pts
			(xy 81.28 50.8) (xy 81.28 52.07)
		)
		(stroke
			(width 0)
			(type default)
		)
	)
	(wire
		(pts
			(xy 40.64 238.76) (xy 66.04 238.76)
		)
		(stroke
			(width 0)
			(type default)
		)
	)
	(wire
		(pts
			(xy 113.03 193.04) (xy 113.03 194.31)
		)
		(stroke
			(width 0)
			(type default)
		)
	)
	(wire
		(pts
			(xy 233.68 110.49) (xy 246.38 110.49)
		)
		(stroke
			(width 0)
			(type default)
		)
	)
	(wire
		(pts
			(xy 115.57 176.53) (xy 113.03 176.53)
		)
		(stroke
			(width 0)
			(type default)
		)
	)
	(wire
		(pts
			(xy 81.28 72.39) (xy 92.71 72.39)
		)
		(stroke
			(width 0)
			(type default)
		)
	)
	(wire
		(pts
			(xy 246.38 161.29) (xy 233.68 161.29)
		)
		(stroke
			(width 0)
			(type default)
		)
	)
	(wire
		(pts
			(xy 40.64 64.77) (xy 58.42 64.77)
		)
		(stroke
			(width 0)
			(type default)
		)
	)
	(wire
		(pts
			(xy 58.42 95.25) (xy 58.42 96.52)
		)
		(stroke
			(width 0)
			(type default)
		)
	)
	(wire
		(pts
			(xy 58.42 222.25) (xy 58.42 223.52)
		)
		(stroke
			(width 0)
			(type default)
		)
	)
	(wire
		(pts
			(xy 66.04 171.45) (xy 73.66 171.45)
		)
		(stroke
			(width 0)
			(type default)
		)
	)
	(wire
		(pts
			(xy 220.98 171.45) (xy 220.98 172.72)
		)
		(stroke
			(width 0)
			(type default)
		)
	)
	(wire
		(pts
			(xy 43.18 95.25) (xy 43.18 96.52)
		)
		(stroke
			(width 0)
			(type default)
		)
	)
	(wire
		(pts
			(xy 111.76 231.14) (xy 113.03 231.14)
		)
		(stroke
			(width 0)
			(type default)
		)
	)
	(wire
		(pts
			(xy 40.64 193.04) (xy 81.28 193.04)
		)
		(stroke
			(width 0)
			(type default)
		)
	)
	(wire
		(pts
			(xy 58.42 64.77) (xy 92.71 64.77)
		)
		(stroke
			(width 0)
			(type default)
		)
	)
	(wire
		(pts
			(xy 58.42 228.6) (xy 58.42 236.22)
		)
		(stroke
			(width 0)
			(type default)
		)
	)
	(wire
		(pts
			(xy 43.18 50.8) (xy 43.18 52.07)
		)
		(stroke
			(width 0)
			(type default)
		)
	)
	(wire
		(pts
			(xy 295.91 140.97) (xy 295.91 127)
		)
		(stroke
			(width 0)
			(type default)
		)
	)
	(wire
		(pts
			(xy 73.66 190.5) (xy 92.71 190.5)
		)
		(stroke
			(width 0)
			(type default)
		)
	)
	(wire
		(pts
			(xy 222.25 148.59) (xy 209.55 148.59)
		)
		(stroke
			(width 0)
			(type default)
		)
	)
	(wire
		(pts
			(xy 81.28 222.25) (xy 81.28 223.52)
		)
		(stroke
			(width 0)
			(type default)
		)
	)
	(wire
		(pts
			(xy 233.68 128.27) (xy 246.38 128.27)
		)
		(stroke
			(width 0)
			(type default)
		)
	)
	(wire
		(pts
			(xy 222.25 140.97) (xy 209.55 140.97)
		)
		(stroke
			(width 0)
			(type default)
		)
	)
	(wire
		(pts
			(xy 40.64 236.22) (xy 58.42 236.22)
		)
		(stroke
			(width 0)
			(type default)
		)
	)
	(wire
		(pts
			(xy 40.64 171.45) (xy 43.18 171.45)
		)
		(stroke
			(width 0)
			(type default)
		)
	)
	(wire
		(pts
			(xy 115.57 55.88) (xy 113.03 55.88)
		)
		(stroke
			(width 0)
			(type default)
		)
	)
	(wire
		(pts
			(xy 50.8 95.25) (xy 50.8 96.52)
		)
		(stroke
			(width 0)
			(type default)
		)
	)
	(wire
		(pts
			(xy 40.64 106.68) (xy 43.18 106.68)
		)
		(stroke
			(width 0)
			(type default)
		)
	)
	(wire
		(pts
			(xy 222.25 146.05) (xy 209.55 146.05)
		)
		(stroke
			(width 0)
			(type default)
		)
	)
	(wire
		(pts
			(xy 58.42 177.8) (xy 58.42 185.42)
		)
		(stroke
			(width 0)
			(type default)
		)
	)
	(wire
		(pts
			(xy 43.18 222.25) (xy 50.8 222.25)
		)
		(stroke
			(width 0)
			(type default)
		)
	)
	(wire
		(pts
			(xy 50.8 101.6) (xy 50.8 104.14)
		)
		(stroke
			(width 0)
			(type default)
		)
	)
	(wire
		(pts
			(xy 233.68 113.03) (xy 246.38 113.03)
		)
		(stroke
			(width 0)
			(type default)
		)
	)
	(wire
		(pts
			(xy 222.25 125.73) (xy 209.55 125.73)
		)
		(stroke
			(width 0)
			(type default)
		)
	)
	(wire
		(pts
			(xy 233.68 133.35) (xy 246.38 133.35)
		)
		(stroke
			(width 0)
			(type default)
		)
	)
	(wire
		(pts
			(xy 40.64 109.22) (xy 58.42 109.22)
		)
		(stroke
			(width 0)
			(type default)
		)
	)
	(wire
		(pts
			(xy 113.03 116.84) (xy 113.03 118.11)
		)
		(stroke
			(width 0)
			(type default)
		)
	)
	(wire
		(pts
			(xy 40.64 69.85) (xy 73.66 69.85)
		)
		(stroke
			(width 0)
			(type default)
		)
	)
	(wire
		(pts
			(xy 222.25 123.19) (xy 209.55 123.19)
		)
		(stroke
			(width 0)
			(type default)
		)
	)
	(wire
		(pts
			(xy 40.64 180.34) (xy 50.8 180.34)
		)
		(stroke
			(width 0)
			(type default)
		)
	)
	(wire
		(pts
			(xy 113.03 234.95) (xy 113.03 231.14)
		)
		(stroke
			(width 0)
			(type default)
		)
	)
	(wire
		(pts
			(xy 325.12 138.43) (xy 325.12 144.78)
		)
		(stroke
			(width 0)
			(type default)
		)
	)
	(wire
		(pts
			(xy 40.64 185.42) (xy 58.42 185.42)
		)
		(stroke
			(width 0)
			(type default)
		)
	)
	(global_label "QSPIB2_CS_N"
		(shape input)
		(at 246.38 128.27 0)
		(fields_autoplaced yes)
		(effects
			(font
				(size 1.27 1.27)
			)
			(justify left)
		)
		(property "Intersheetrefs" "${INTERSHEET_REFS}"
			(at 0.635 0.635 0)
			(effects
				(font
					(size 1.27 1.27)
				)
				(hide yes)
			)
		)
	)
	(global_label "QSPIB2_CS_N"
		(shape input)
		(at 40.64 243.84 180)
		(fields_autoplaced yes)
		(effects
			(font
				(size 1.27 1.27)
			)
			(justify right)
		)
		(property "Intersheetrefs" "${INTERSHEET_REFS}"
			(at -6.35 1.27 0)
			(effects
				(font
					(size 1.27 1.27)
				)
				(hide yes)
			)
		)
	)
	(global_label "QSPIA2_CS_N"
		(shape input)
		(at 40.64 116.84 180)
		(fields_autoplaced yes)
		(effects
			(font
				(size 1.27 1.27)
			)
			(justify right)
		)
		(property "Intersheetrefs" "${INTERSHEET_REFS}"
			(at -8.255 0 0)
			(effects
				(font
					(size 1.27 1.27)
				)
				(hide yes)
			)
		)
	)
	(global_label "QSPIB1_D2"
		(shape input)
		(at 40.64 185.42 180)
		(fields_autoplaced yes)
		(effects
			(font
				(size 1.27 1.27)
			)
			(justify right)
		)
		(property "Intersheetrefs" "${INTERSHEET_REFS}"
			(at -6.985 -7.62 0)
			(effects
				(font
					(size 1.27 1.27)
				)
				(hide yes)
			)
		)
	)
	(global_label "ROT_GPIO1"
		(shape input)
		(at 246.38 166.37 0)
		(fields_autoplaced yes)
		(effects
			(font
				(size 1.27 1.27)
			)
			(justify left)
		)
		(property "Intersheetrefs" "${INTERSHEET_REFS}"
			(at 0.635 0.635 0)
			(effects
				(font
					(size 1.27 1.27)
				)
				(hide yes)
			)
		)
	)
	(global_label "QSPIA2_CS_N"
		(shape input)
		(at 246.38 156.21 0)
		(fields_autoplaced yes)
		(effects
			(font
				(size 1.27 1.27)
			)
			(justify left)
		)
		(property "Intersheetrefs" "${INTERSHEET_REFS}"
			(at 0.635 0.635 0)
			(effects
				(font
					(size 1.27 1.27)
				)
				(hide yes)
			)
		)
	)
	(global_label "VCC3V3"
		(shape input)
		(at 335.28 127 90)
		(fields_autoplaced yes)
		(effects
			(font
				(size 1.27 1.27)
			)
			(justify left)
		)
		(property "Intersheetrefs" "${INTERSHEET_REFS}"
			(at 0 0 0)
			(effects
				(font
					(size 1.27 1.27)
				)
				(hide yes)
			)
		)
	)
	(global_label "QSPIB2_D2"
		(shape input)
		(at 246.38 133.35 0)
		(fields_autoplaced yes)
		(effects
			(font
				(size 1.27 1.27)
			)
			(justify left)
		)
		(property "Intersheetrefs" "${INTERSHEET_REFS}"
			(at 0.635 0.635 0)
			(effects
				(font
					(size 1.27 1.27)
				)
				(hide yes)
			)
		)
	)
	(global_label "VCC3V3"
		(shape input)
		(at 40.64 171.45 180)
		(fields_autoplaced yes)
		(effects
			(font
				(size 1.27 1.27)
			)
			(justify right)
		)
		(property "Intersheetrefs" "${INTERSHEET_REFS}"
			(at -6.35 269.24 0)
			(effects
				(font
					(size 1.27 1.27)
				)
				(hide yes)
			)
		)
	)
	(global_label "QSPIB2_D0"
		(shape input)
		(at 246.38 120.65 0)
		(fields_autoplaced yes)
		(effects
			(font
				(size 1.27 1.27)
			)
			(justify left)
		)
		(property "Intersheetrefs" "${INTERSHEET_REFS}"
			(at 0.635 0.635 0)
			(effects
				(font
					(size 1.27 1.27)
				)
				(hide yes)
			)
		)
	)
	(global_label "QSPI0_D2"
		(shape input)
		(at 209.55 140.97 180)
		(fields_autoplaced yes)
		(effects
			(font
				(size 1.27 1.27)
			)
			(justify right)
		)
		(property "Intersheetrefs" "${INTERSHEET_REFS}"
			(at 0.635 0.635 0)
			(effects
				(font
					(size 1.27 1.27)
				)
				(hide yes)
			)
		)
	)
	(global_label "QSPIA_CLK"
		(shape input)
		(at 246.38 151.13 0)
		(fields_autoplaced yes)
		(effects
			(font
				(size 1.27 1.27)
			)
			(justify left)
		)
		(property "Intersheetrefs" "${INTERSHEET_REFS}"
			(at 0.635 0.635 0)
			(effects
				(font
					(size 1.27 1.27)
				)
				(hide yes)
			)
		)
	)
	(global_label "QSPI0_D3"
		(shape input)
		(at 209.55 138.43 180)
		(fields_autoplaced yes)
		(effects
			(font
				(size 1.27 1.27)
			)
			(justify right)
		)
		(property "Intersheetrefs" "${INTERSHEET_REFS}"
			(at 0.635 0.635 0)
			(effects
				(font
					(size 1.27 1.27)
				)
				(hide yes)
			)
		)
	)
	(global_label "ROT_SS"
		(shape input)
		(at 246.38 115.57 0)
		(fields_autoplaced yes)
		(effects
			(font
				(size 1.27 1.27)
			)
			(justify left)
		)
		(property "Intersheetrefs" "${INTERSHEET_REFS}"
			(at 0.635 0.635 0)
			(effects
				(font
					(size 1.27 1.27)
				)
				(hide yes)
			)
		)
	)
	(global_label "ROT_QSPI_DQ3"
		(shape input)
		(at 209.55 133.35 180)
		(fields_autoplaced yes)
		(effects
			(font
				(size 1.27 1.27)
			)
			(justify right)
		)
		(property "Intersheetrefs" "${INTERSHEET_REFS}"
			(at 0.635 0.635 0)
			(effects
				(font
					(size 1.27 1.27)
				)
				(hide yes)
			)
		)
	)
	(global_label "QSPIA1_D3"
		(shape input)
		(at 209.55 156.21 180)
		(fields_autoplaced yes)
		(effects
			(font
				(size 1.27 1.27)
			)
			(justify right)
		)
		(property "Intersheetrefs" "${INTERSHEET_REFS}"
			(at 0.635 0.635 0)
			(effects
				(font
					(size 1.27 1.27)
				)
				(hide yes)
			)
		)
	)
	(global_label "PROGRAM"
		(shape input)
		(at 209.55 123.19 180)
		(fields_autoplaced yes)
		(effects
			(font
				(size 1.27 1.27)
			)
			(justify right)
		)
		(property "Intersheetrefs" "${INTERSHEET_REFS}"
			(at 0.635 0.635 0)
			(effects
				(font
					(size 1.27 1.27)
				)
				(hide yes)
			)
		)
	)
	(global_label "VCC3V3"
		(shape input)
		(at 115.57 55.88 0)
		(fields_autoplaced yes)
		(effects
			(font
				(size 1.27 1.27)
			)
			(justify left)
		)
		(property "Intersheetrefs" "${INTERSHEET_REFS}"
			(at 162.56 -41.91 0)
			(effects
				(font
					(size 1.27 1.27)
				)
				(hide yes)
			)
		)
	)
	(global_label "VCC3V3"
		(shape input)
		(at 115.57 227.33 0)
		(fields_autoplaced yes)
		(effects
			(font
				(size 1.27 1.27)
			)
			(justify left)
		)
		(property "Intersheetrefs" "${INTERSHEET_REFS}"
			(at 162.56 129.54 0)
			(effects
				(font
					(size 1.27 1.27)
				)
				(hide yes)
			)
		)
	)
	(global_label "QSPIB_CLK"
		(shape input)
		(at 40.64 190.5 180)
		(fields_autoplaced yes)
		(effects
			(font
				(size 1.27 1.27)
			)
			(justify right)
		)
		(property "Intersheetrefs" "${INTERSHEET_REFS}"
			(at -6.985 -7.62 0)
			(effects
				(font
					(size 1.27 1.27)
				)
				(hide yes)
			)
		)
	)
	(global_label "QSPIB2_D3"
		(shape input)
		(at 40.64 238.76 180)
		(fields_autoplaced yes)
		(effects
			(font
				(size 1.27 1.27)
			)
			(justify right)
		)
		(property "Intersheetrefs" "${INTERSHEET_REFS}"
			(at -6.35 -13.97 0)
			(effects
				(font
					(size 1.27 1.27)
				)
				(hide yes)
			)
		)
	)
	(global_label "VCC3V3"
		(shape input)
		(at 40.64 95.25 180)
		(fields_autoplaced yes)
		(effects
			(font
				(size 1.27 1.27)
			)
			(justify right)
		)
		(property "Intersheetrefs" "${INTERSHEET_REFS}"
			(at -6.35 193.04 0)
			(effects
				(font
					(size 1.27 1.27)
				)
				(hide yes)
			)
		)
	)
	(global_label "TPM_PP"
		(shape input)
		(at 322.58 135.89 0)
		(fields_autoplaced yes)
		(effects
			(font
				(size 1.27 1.27)
			)
			(justify left)
		)
		(property "Intersheetrefs" "${INTERSHEET_REFS}"
			(at 0.635 0 0)
			(effects
				(font
					(size 1.27 1.27)
				)
				(hide yes)
			)
		)
	)
	(global_label "VCC3V3"
		(shape input)
		(at 115.57 100.33 0)
		(fields_autoplaced yes)
		(effects
			(font
				(size 1.27 1.27)
			)
			(justify left)
		)
		(property "Intersheetrefs" "${INTERSHEET_REFS}"
			(at 162.56 2.54 0)
			(effects
				(font
					(size 1.27 1.27)
				)
				(hide yes)
			)
		)
	)
	(global_label "VCC3V3"
		(shape input)
		(at 40.64 50.8 180)
		(fields_autoplaced yes)
		(effects
			(font
				(size 1.27 1.27)
			)
			(justify right)
		)
		(property "Intersheetrefs" "${INTERSHEET_REFS}"
			(at -6.35 148.59 0)
			(effects
				(font
					(size 1.27 1.27)
				)
				(hide yes)
			)
		)
	)
	(global_label "QSPIA1_D0"
		(shape input)
		(at 209.55 153.67 180)
		(fields_autoplaced yes)
		(effects
			(font
				(size 1.27 1.27)
			)
			(justify right)
		)
		(property "Intersheetrefs" "${INTERSHEET_REFS}"
			(at 0.635 0.635 0)
			(effects
				(font
					(size 1.27 1.27)
				)
				(hide yes)
			)
		)
	)
	(global_label "QSPIA_CLK"
		(shape input)
		(at 40.64 114.3 180)
		(fields_autoplaced yes)
		(effects
			(font
				(size 1.27 1.27)
			)
			(justify right)
		)
		(property "Intersheetrefs" "${INTERSHEET_REFS}"
			(at -8.255 -10.16 0)
			(effects
				(font
					(size 1.27 1.27)
				)
				(hide yes)
			)
		)
	)
	(global_label "QSPIA_CLK"
		(shape input)
		(at 40.64 69.85 180)
		(fields_autoplaced yes)
		(effects
			(font
				(size 1.27 1.27)
			)
			(justify right)
		)
		(property "Intersheetrefs" "${INTERSHEET_REFS}"
			(at -8.89 -2.54 0)
			(effects
				(font
					(size 1.27 1.27)
				)
				(hide yes)
			)
		)
	)
	(global_label "ROT_GPIO2"
		(shape input)
		(at 209.55 166.37 180)
		(fields_autoplaced yes)
		(effects
			(font
				(size 1.27 1.27)
			)
			(justify right)
		)
		(property "Intersheetrefs" "${INTERSHEET_REFS}"
			(at 0.635 0.635 0)
			(effects
				(font
					(size 1.27 1.27)
				)
				(hide yes)
			)
		)
	)
	(global_label "SPI0_CLK"
		(shape input)
		(at 312.42 135.89 180)
		(fields_autoplaced yes)
		(effects
			(font
				(size 1.27 1.27)
			)
			(justify right)
		)
		(property "Intersheetrefs" "${INTERSHEET_REFS}"
			(at 0.635 0 0)
			(effects
				(font
					(size 1.27 1.27)
				)
				(hide yes)
			)
		)
	)
	(global_label "QSPI0_CLK"
		(shape input)
		(at 209.55 151.13 180)
		(fields_autoplaced yes)
		(effects
			(font
				(size 1.27 1.27)
			)
			(justify right)
		)
		(property "Intersheetrefs" "${INTERSHEET_REFS}"
			(at 0.635 0.635 0)
			(effects
				(font
					(size 1.27 1.27)
				)
				(hide yes)
			)
		)
	)
	(global_label "QSPIB_CLK"
		(shape input)
		(at 40.64 241.3 180)
		(fields_autoplaced yes)
		(effects
			(font
				(size 1.27 1.27)
			)
			(justify right)
		)
		(property "Intersheetrefs" "${INTERSHEET_REFS}"
			(at -6.35 -8.89 0)
			(effects
				(font
					(size 1.27 1.27)
				)
				(hide yes)
			)
		)
	)
	(global_label "ROT_MOSI"
		(shape input)
		(at 246.38 110.49 0)
		(fields_autoplaced yes)
		(effects
			(font
				(size 1.27 1.27)
			)
			(justify left)
		)
		(property "Intersheetrefs" "${INTERSHEET_REFS}"
			(at 0.635 0.635 0)
			(effects
				(font
					(size 1.27 1.27)
				)
				(hide yes)
			)
		)
	)
	(global_label "SPI0_CS_N"
		(shape input)
		(at 312.42 128.27 180)
		(fields_autoplaced yes)
		(effects
			(font
				(size 1.27 1.27)
			)
			(justify right)
		)
		(property "Intersheetrefs" "${INTERSHEET_REFS}"
			(at 0.635 0 0)
			(effects
				(font
					(size 1.27 1.27)
				)
				(hide yes)
			)
		)
	)
	(global_label "ROT_QSPI_SCK"
		(shape input)
		(at 209.55 135.89 180)
		(fields_autoplaced yes)
		(effects
			(font
				(size 1.27 1.27)
			)
			(justify right)
		)
		(property "Intersheetrefs" "${INTERSHEET_REFS}"
			(at 0.635 0.635 0)
			(effects
				(font
					(size 1.27 1.27)
				)
				(hide yes)
			)
		)
	)
	(global_label "QSPIA2_D1"
		(shape input)
		(at 40.64 106.68 180)
		(fields_autoplaced yes)
		(effects
			(font
				(size 1.27 1.27)
			)
			(justify right)
		)
		(property "Intersheetrefs" "${INTERSHEET_REFS}"
			(at 140.335 -15.24 0)
			(effects
				(font
					(size 1.27 1.27)
				)
				(justify left)
				(hide yes)
			)
		)
	)
	(global_label "QSPIB2_D0"
		(shape input)
		(at 40.64 231.14 180)
		(fields_autoplaced yes)
		(effects
			(font
				(size 1.27 1.27)
			)
			(justify right)
		)
		(property "Intersheetrefs" "${INTERSHEET_REFS}"
			(at -6.35 -16.51 0)
			(effects
				(font
					(size 1.27 1.27)
				)
				(hide yes)
			)
		)
	)
	(global_label "ROT_RDY\\ROT_GPIO0"
		(shape input)
		(at 209.55 118.11 180)
		(fields_autoplaced yes)
		(effects
			(font
				(size 1.27 1.27)
			)
			(justify right)
		)
		(property "Intersheetrefs" "${INTERSHEET_REFS}"
			(at 0.635 0.635 0)
			(effects
				(font
					(size 1.27 1.27)
				)
				(hide yes)
			)
		)
	)
	(global_label "ROT_QSPI_DQ0"
		(shape input)
		(at 209.55 125.73 180)
		(fields_autoplaced yes)
		(effects
			(font
				(size 1.27 1.27)
			)
			(justify right)
		)
		(property "Intersheetrefs" "${INTERSHEET_REFS}"
			(at 0.635 0.635 0)
			(effects
				(font
					(size 1.27 1.27)
				)
				(hide yes)
			)
		)
	)
	(global_label "QSPIB1_D0"
		(shape input)
		(at 40.64 180.34 180)
		(fields_autoplaced yes)
		(effects
			(font
				(size 1.27 1.27)
			)
			(justify right)
		)
		(property "Intersheetrefs" "${INTERSHEET_REFS}"
			(at -6.985 -15.24 0)
			(effects
				(font
					(size 1.27 1.27)
				)
				(hide yes)
			)
		)
	)
	(global_label "SPI0_MISO"
		(shape input)
		(at 312.42 133.35 180)
		(fields_autoplaced yes)
		(effects
			(font
				(size 1.27 1.27)
			)
			(justify right)
		)
		(property "Intersheetrefs" "${INTERSHEET_REFS}"
			(at 0.635 0 0)
			(effects
				(font
					(size 1.27 1.27)
				)
				(hide yes)
			)
		)
	)
	(global_label "ROT_TX"
		(shape input)
		(at 209.55 115.57 180)
		(fields_autoplaced yes)
		(effects
			(font
				(size 1.27 1.27)
			)
			(justify right)
		)
		(property "Intersheetrefs" "${INTERSHEET_REFS}"
			(at 0.635 0.635 0)
			(effects
				(font
					(size 1.27 1.27)
				)
				(hide yes)
			)
		)
	)
	(global_label "QSPIB1_D3"
		(shape input)
		(at 40.64 187.96 180)
		(fields_autoplaced yes)
		(effects
			(font
				(size 1.27 1.27)
			)
			(justify right)
		)
		(property "Intersheetrefs" "${INTERSHEET_REFS}"
			(at -6.985 -12.7 0)
			(effects
				(font
					(size 1.27 1.27)
				)
				(hide yes)
			)
		)
	)
	(global_label "QSPIA2_D1"
		(shape input)
		(at 246.38 158.75 0)
		(fields_autoplaced yes)
		(effects
			(font
				(size 1.27 1.27)
			)
			(justify left)
		)
		(property "Intersheetrefs" "${INTERSHEET_REFS}"
			(at 0.635 0.635 0)
			(effects
				(font
					(size 1.27 1.27)
				)
				(hide yes)
			)
		)
	)
	(global_label "SPI0_MOSI"
		(shape input)
		(at 312.42 130.81 180)
		(fields_autoplaced yes)
		(effects
			(font
				(size 1.27 1.27)
			)
			(justify right)
		)
		(property "Intersheetrefs" "${INTERSHEET_REFS}"
			(at 0.635 0 0)
			(effects
				(font
					(size 1.27 1.27)
				)
				(hide yes)
			)
		)
	)
	(global_label "QSPIA1_D2"
		(shape input)
		(at 209.55 163.83 180)
		(fields_autoplaced yes)
		(effects
			(font
				(size 1.27 1.27)
			)
			(justify right)
		)
		(property "Intersheetrefs" "${INTERSHEET_REFS}"
			(at 0.635 0.635 0)
			(effects
				(font
					(size 1.27 1.27)
				)
				(hide yes)
			)
		)
	)
	(global_label "QSPI0_CS0_N"
		(shape input)
		(at 209.55 148.59 180)
		(fields_autoplaced yes)
		(effects
			(font
				(size 1.27 1.27)
			)
			(justify right)
		)
		(property "Intersheetrefs" "${INTERSHEET_REFS}"
			(at 0.635 0.635 0)
			(effects
				(font
					(size 1.27 1.27)
				)
				(hide yes)
			)
		)
	)
	(global_label "VCC3V3"
		(shape input)
		(at 295.91 127 90)
		(fields_autoplaced yes)
		(effects
			(font
				(size 1.27 1.27)
			)
			(justify left)
		)
		(property "Intersheetrefs" "${INTERSHEET_REFS}"
			(at 0 0 0)
			(effects
				(font
					(size 1.27 1.27)
				)
				(hide yes)
			)
		)
	)
	(global_label "VCC3V3"
		(shape input)
		(at 248.92 168.91 0)
		(fields_autoplaced yes)
		(effects
			(font
				(size 1.27 1.27)
			)
			(justify left)
		)
		(property "Intersheetrefs" "${INTERSHEET_REFS}"
			(at 0.635 0.635 0)
			(effects
				(font
					(size 1.27 1.27)
				)
				(hide yes)
			)
		)
	)
	(global_label "QSPIB2_D1"
		(shape input)
		(at 40.64 233.68 180)
		(fields_autoplaced yes)
		(effects
			(font
				(size 1.27 1.27)
			)
			(justify right)
		)
		(property "Intersheetrefs" "${INTERSHEET_REFS}"
			(at 138.43 -13.97 0)
			(effects
				(font
					(size 1.27 1.27)
				)
				(justify left)
				(hide yes)
			)
		)
	)
	(global_label "QSPIA1_D0"
		(shape input)
		(at 40.64 59.69 180)
		(fields_autoplaced yes)
		(effects
			(font
				(size 1.27 1.27)
			)
			(justify right)
		)
		(property "Intersheetrefs" "${INTERSHEET_REFS}"
			(at -8.89 -10.16 0)
			(effects
				(font
					(size 1.27 1.27)
				)
				(hide yes)
			)
		)
	)
	(global_label "ROT_QSPI_DQ2"
		(shape input)
		(at 209.55 130.81 180)
		(fields_autoplaced yes)
		(effects
			(font
				(size 1.27 1.27)
			)
			(justify right)
		)
		(property "Intersheetrefs" "${INTERSHEET_REFS}"
			(at 0.635 0.635 0)
			(effects
				(font
					(size 1.27 1.27)
				)
				(hide yes)
			)
		)
	)
	(global_label "TPM_GPIO"
		(shape input)
		(at 322.58 133.35 0)
		(fields_autoplaced yes)
		(effects
			(font
				(size 1.27 1.27)
			)
			(justify left)
		)
		(property "Intersheetrefs" "${INTERSHEET_REFS}"
			(at 0.635 0 0)
			(effects
				(font
					(size 1.27 1.27)
				)
				(hide yes)
			)
		)
	)
	(global_label "QSPIA1_D1"
		(shape input)
		(at 40.64 62.23 180)
		(fields_autoplaced yes)
		(effects
			(font
				(size 1.27 1.27)
			)
			(justify right)
		)
		(property "Intersheetrefs" "${INTERSHEET_REFS}"
			(at 140.97 -7.62 0)
			(effects
				(font
					(size 1.27 1.27)
				)
				(justify left)
				(hide yes)
			)
		)
	)
	(global_label "QSPIB1_D3"
		(shape input)
		(at 246.38 138.43 0)
		(fields_autoplaced yes)
		(effects
			(font
				(size 1.27 1.27)
			)
			(justify left)
		)
		(property "Intersheetrefs" "${INTERSHEET_REFS}"
			(at 0.635 0.635 0)
			(effects
				(font
					(size 1.27 1.27)
				)
				(hide yes)
			)
		)
	)
	(global_label "QSPI0_CS1_N"
		(shape input)
		(at 246.38 163.83 0)
		(fields_autoplaced yes)
		(effects
			(font
				(size 1.27 1.27)
			)
			(justify left)
		)
		(property "Intersheetrefs" "${INTERSHEET_REFS}"
			(at 0.635 0.635 0)
			(effects
				(font
					(size 1.27 1.27)
				)
				(hide yes)
			)
		)
	)
	(global_label "QSPIA2_D3"
		(shape input)
		(at 40.64 111.76 180)
		(fields_autoplaced yes)
		(effects
			(font
				(size 1.27 1.27)
			)
			(justify right)
		)
		(property "Intersheetrefs" "${INTERSHEET_REFS}"
			(at -8.255 -15.24 0)
			(effects
				(font
					(size 1.27 1.27)
				)
				(hide yes)
			)
		)
	)
	(global_label "QSPIA2_D2"
		(shape input)
		(at 246.38 161.29 0)
		(fields_autoplaced yes)
		(effects
			(font
				(size 1.27 1.27)
			)
			(justify left)
		)
		(property "Intersheetrefs" "${INTERSHEET_REFS}"
			(at 0.635 0.635 0)
			(effects
				(font
					(size 1.27 1.27)
				)
				(hide yes)
			)
		)
	)
	(global_label "QSPIB1_CS_N"
		(shape input)
		(at 246.38 140.97 0)
		(fields_autoplaced yes)
		(effects
			(font
				(size 1.27 1.27)
			)
			(justify left)
		)
		(property "Intersheetrefs" "${INTERSHEET_REFS}"
			(at 0.635 0.635 0)
			(effects
				(font
					(size 1.27 1.27)
				)
				(hide yes)
			)
		)
	)
	(global_label "ROT_RX"
		(shape input)
		(at 209.55 113.03 180)
		(fields_autoplaced yes)
		(effects
			(font
				(size 1.27 1.27)
			)
			(justify right)
		)
		(property "Intersheetrefs" "${INTERSHEET_REFS}"
			(at 0.635 0.635 0)
			(effects
				(font
					(size 1.27 1.27)
				)
				(hide yes)
			)
		)
	)
	(global_label "QSPIA1_CS_N"
		(shape input)
		(at 40.64 72.39 180)
		(fields_autoplaced yes)
		(effects
			(font
				(size 1.27 1.27)
			)
			(justify right)
		)
		(property "Intersheetrefs" "${INTERSHEET_REFS}"
			(at -8.89 7.62 0)
			(effects
				(font
					(size 1.27 1.27)
				)
				(hide yes)
			)
		)
	)
	(global_label "ROT_QSPI_CS_B"
		(shape input)
		(at 246.38 118.11 0)
		(fields_autoplaced yes)
		(effects
			(font
				(size 1.27 1.27)
			)
			(justify left)
		)
		(property "Intersheetrefs" "${INTERSHEET_REFS}"
			(at 0.635 0.635 0)
			(effects
				(font
					(size 1.27 1.27)
				)
				(hide yes)
			)
		)
	)
	(global_label "TPM_RST"
		(shape input)
		(at 322.58 130.81 0)
		(fields_autoplaced yes)
		(effects
			(font
				(size 1.27 1.27)
			)
			(justify left)
		)
		(property "Intersheetrefs" "${INTERSHEET_REFS}"
			(at 0.635 0 0)
			(effects
				(font
					(size 1.27 1.27)
				)
				(hide yes)
			)
		)
	)
	(global_label "QSPIB_CLK"
		(shape input)
		(at 246.38 123.19 0)
		(fields_autoplaced yes)
		(effects
			(font
				(size 1.27 1.27)
			)
			(justify left)
		)
		(property "Intersheetrefs" "${INTERSHEET_REFS}"
			(at 0.635 0.635 0)
			(effects
				(font
					(size 1.27 1.27)
				)
				(hide yes)
			)
		)
	)
	(global_label "QSPIA1_D1"
		(shape input)
		(at 209.55 161.29 180)
		(fields_autoplaced yes)
		(effects
			(font
				(size 1.27 1.27)
			)
			(justify right)
		)
		(property "Intersheetrefs" "${INTERSHEET_REFS}"
			(at 0.635 0.635 0)
			(effects
				(font
					(size 1.27 1.27)
				)
				(hide yes)
			)
		)
	)
	(global_label "INIT"
		(shape input)
		(at 209.55 120.65 180)
		(fields_autoplaced yes)
		(effects
			(font
				(size 1.27 1.27)
			)
			(justify right)
		)
		(property "Intersheetrefs" "${INTERSHEET_REFS}"
			(at 0.635 0.635 0)
			(effects
				(font
					(size 1.27 1.27)
				)
				(hide yes)
			)
		)
	)
	(global_label "QSPI0_D1"
		(shape input)
		(at 209.55 143.51 180)
		(fields_autoplaced yes)
		(effects
			(font
				(size 1.27 1.27)
			)
			(justify right)
		)
		(property "Intersheetrefs" "${INTERSHEET_REFS}"
			(at 0.635 0.635 0)
			(effects
				(font
					(size 1.27 1.27)
				)
				(hide yes)
			)
		)
	)
	(global_label "QSPIB1_D2"
		(shape input)
		(at 246.38 146.05 0)
		(fields_autoplaced yes)
		(effects
			(font
				(size 1.27 1.27)
			)
			(justify left)
		)
		(property "Intersheetrefs" "${INTERSHEET_REFS}"
			(at 0.635 0.635 0)
			(effects
				(font
					(size 1.27 1.27)
				)
				(hide yes)
			)
		)
	)
	(global_label "TPM_PIRQ#"
		(shape input)
		(at 322.58 128.27 0)
		(fields_autoplaced yes)
		(effects
			(font
				(size 1.27 1.27)
			)
			(justify left)
		)
		(property "Intersheetrefs" "${INTERSHEET_REFS}"
			(at 0.635 0 0)
			(effects
				(font
					(size 1.27 1.27)
				)
				(hide yes)
			)
		)
	)
	(global_label "ROT_SCLK"
		(shape input)
		(at 209.55 110.49 180)
		(fields_autoplaced yes)
		(effects
			(font
				(size 1.27 1.27)
			)
			(justify right)
		)
		(property "Intersheetrefs" "${INTERSHEET_REFS}"
			(at 0.635 0.635 0)
			(effects
				(font
					(size 1.27 1.27)
				)
				(hide yes)
			)
		)
	)
	(global_label "QSPIB1_CS_N"
		(shape input)
		(at 40.64 193.04 180)
		(fields_autoplaced yes)
		(effects
			(font
				(size 1.27 1.27)
			)
			(justify right)
		)
		(property "Intersheetrefs" "${INTERSHEET_REFS}"
			(at -6.985 2.54 0)
			(effects
				(font
					(size 1.27 1.27)
				)
				(hide yes)
			)
		)
	)
	(global_label "QSPIA2_D0"
		(shape input)
		(at 40.64 104.14 180)
		(fields_autoplaced yes)
		(effects
			(font
				(size 1.27 1.27)
			)
			(justify right)
		)
		(property "Intersheetrefs" "${INTERSHEET_REFS}"
			(at -8.255 -17.78 0)
			(effects
				(font
					(size 1.27 1.27)
				)
				(hide yes)
			)
		)
	)
	(global_label "QSPIA1_CS_N"
		(shape input)
		(at 209.55 158.75 180)
		(fields_autoplaced yes)
		(effects
			(font
				(size 1.27 1.27)
			)
			(justify right)
		)
		(property "Intersheetrefs" "${INTERSHEET_REFS}"
			(at 0.635 0.635 0)
			(effects
				(font
					(size 1.27 1.27)
				)
				(hide yes)
			)
		)
	)
	(global_label "QSPI0_D0"
		(shape input)
		(at 209.55 146.05 180)
		(fields_autoplaced yes)
		(effects
			(font
				(size 1.27 1.27)
			)
			(justify right)
		)
		(property "Intersheetrefs" "${INTERSHEET_REFS}"
			(at 0.635 0.635 0)
			(effects
				(font
					(size 1.27 1.27)
				)
				(hide yes)
			)
		)
	)
	(global_label "QSPIA2_D3"
		(shape input)
		(at 246.38 153.67 0)
		(fields_autoplaced yes)
		(effects
			(font
				(size 1.27 1.27)
			)
			(justify left)
		)
		(property "Intersheetrefs" "${INTERSHEET_REFS}"
			(at 0.635 0.635 0)
			(effects
				(font
					(size 1.27 1.27)
				)
				(hide yes)
			)
		)
	)
	(global_label "QSPIB2_D2"
		(shape input)
		(at 40.64 236.22 180)
		(fields_autoplaced yes)
		(effects
			(font
				(size 1.27 1.27)
			)
			(justify right)
		)
		(property "Intersheetrefs" "${INTERSHEET_REFS}"
			(at -6.35 -8.89 0)
			(effects
				(font
					(size 1.27 1.27)
				)
				(hide yes)
			)
		)
	)
	(global_label "QSPIB2_D1"
		(shape input)
		(at 246.38 130.81 0)
		(fields_autoplaced yes)
		(effects
			(font
				(size 1.27 1.27)
			)
			(justify left)
		)
		(property "Intersheetrefs" "${INTERSHEET_REFS}"
			(at 0.635 0.635 0)
			(effects
				(font
					(size 1.27 1.27)
				)
				(hide yes)
			)
		)
	)
	(global_label "QSPIA2_D0"
		(shape input)
		(at 246.38 148.59 0)
		(fields_autoplaced yes)
		(effects
			(font
				(size 1.27 1.27)
			)
			(justify left)
		)
		(property "Intersheetrefs" "${INTERSHEET_REFS}"
			(at 0.635 0.635 0)
			(effects
				(font
					(size 1.27 1.27)
				)
				(hide yes)
			)
		)
	)
	(global_label "ROT_QSPI_DQ1"
		(shape input)
		(at 209.55 128.27 180)
		(fields_autoplaced yes)
		(effects
			(font
				(size 1.27 1.27)
			)
			(justify right)
		)
		(property "Intersheetrefs" "${INTERSHEET_REFS}"
			(at 0.635 0.635 0)
			(effects
				(font
					(size 1.27 1.27)
				)
				(hide yes)
			)
		)
	)
	(global_label "QSPIB1_D1"
		(shape input)
		(at 40.64 182.88 180)
		(fields_autoplaced yes)
		(effects
			(font
				(size 1.27 1.27)
			)
			(justify right)
		)
		(property "Intersheetrefs" "${INTERSHEET_REFS}"
			(at 139.065 -12.7 0)
			(effects
				(font
					(size 1.27 1.27)
				)
				(justify left)
				(hide yes)
			)
		)
	)
	(global_label "QSPIB1_D1"
		(shape input)
		(at 246.38 143.51 0)
		(fields_autoplaced yes)
		(effects
			(font
				(size 1.27 1.27)
			)
			(justify left)
		)
		(property "Intersheetrefs" "${INTERSHEET_REFS}"
			(at 0.635 0.635 0)
			(effects
				(font
					(size 1.27 1.27)
				)
				(hide yes)
			)
		)
	)
	(global_label "VCC3V3"
		(shape input)
		(at 115.57 176.53 0)
		(fields_autoplaced yes)
		(effects
			(font
				(size 1.27 1.27)
			)
			(justify left)
		)
		(property "Intersheetrefs" "${INTERSHEET_REFS}"
			(at 162.56 78.74 0)
			(effects
				(font
					(size 1.27 1.27)
				)
				(hide yes)
			)
		)
	)
	(global_label "QSPIA1_D2"
		(shape input)
		(at 40.64 64.77 180)
		(fields_autoplaced yes)
		(effects
			(font
				(size 1.27 1.27)
			)
			(justify right)
		)
		(property "Intersheetrefs" "${INTERSHEET_REFS}"
			(at -8.89 -2.54 0)
			(effects
				(font
					(size 1.27 1.27)
				)
				(hide yes)
			)
		)
	)
	(global_label "QSPIA2_D2"
		(shape input)
		(at 40.64 109.22 180)
		(fields_autoplaced yes)
		(effects
			(font
				(size 1.27 1.27)
			)
			(justify right)
		)
		(property "Intersheetrefs" "${INTERSHEET_REFS}"
			(at -8.255 -10.16 0)
			(effects
				(font
					(size 1.27 1.27)
				)
				(hide yes)
			)
		)
	)
	(global_label "QSPIB1_D0"
		(shape input)
		(at 246.38 135.89 0)
		(fields_autoplaced yes)
		(effects
			(font
				(size 1.27 1.27)
			)
			(justify left)
		)
		(property "Intersheetrefs" "${INTERSHEET_REFS}"
			(at 0.635 0.635 0)
			(effects
				(font
					(size 1.27 1.27)
				)
				(hide yes)
			)
		)
	)
	(global_label "QSPIA1_D3"
		(shape input)
		(at 40.64 67.31 180)
		(fields_autoplaced yes)
		(effects
			(font
				(size 1.27 1.27)
			)
			(justify right)
		)
		(property "Intersheetrefs" "${INTERSHEET_REFS}"
			(at -8.89 -7.62 0)
			(effects
				(font
					(size 1.27 1.27)
				)
				(hide yes)
			)
		)
	)
	(global_label "ROT_MISO"
		(shape input)
		(at 246.38 113.03 0)
		(fields_autoplaced yes)
		(effects
			(font
				(size 1.27 1.27)
			)
			(justify left)
		)
		(property "Intersheetrefs" "${INTERSHEET_REFS}"
			(at 0.635 0.635 0)
			(effects
				(font
					(size 1.27 1.27)
				)
				(hide yes)
			)
		)
	)
	(global_label "QSPIB2_D3"
		(shape input)
		(at 246.38 125.73 0)
		(fields_autoplaced yes)
		(effects
			(font
				(size 1.27 1.27)
			)
			(justify left)
		)
		(property "Intersheetrefs" "${INTERSHEET_REFS}"
			(at 0.635 0.635 0)
			(effects
				(font
					(size 1.27 1.27)
				)
				(hide yes)
			)
		)
	)
	(global_label "VCC3V3"
		(shape input)
		(at 40.64 222.25 180)
		(fields_autoplaced yes)
		(effects
			(font
				(size 1.27 1.27)
			)
			(justify right)
		)
		(property "Intersheetrefs" "${INTERSHEET_REFS}"
			(at -6.35 320.04 0)
			(effects
				(font
					(size 1.27 1.27)
				)
				(hide yes)
			)
		)
	)
	(symbol
		(lib_id "antmicroResistors0402:R_4k7_0402")
		(at 81.28 52.07 270)
		(unit 1)
		(exclude_from_sim no)
		(in_bom yes)
		(on_board yes)
		(dnp no)
		(property "Reference" "R24"
			(at 82.55 53.34 90)
			(effects
				(font
					(size 1.27 1.27)
				)
				(justify left)
			)
		)
		(property "Value" "R_4k7_0402"
			(at 68.58 72.39 0)
			(effects
				(font
					(size 1.27 1.27)
					(thickness 0.15)
				)
				(justify left bottom)
				(hide yes)
			)
		)
		(property "Footprint" "antmicro-footprints:R_0402_1005Metric"
			(at 66.04 72.39 0)
			(effects
				(font
					(size 1.27 1.27)
					(thickness 0.15)
				)
				(justify left bottom)
				(hide yes)
			)
		)
		(property "Datasheet" "https://www.bourns.com/docs/product-datasheets/cr.pdf"
			(at 63.5 72.39 0)
			(effects
				(font
					(size 1.27 1.27)
					(thickness 0.15)
				)
				(justify left bottom)
				(hide yes)
			)
		)
		(property "Description" "SMD Chip Resistor, 4.7 kohm, ± 1%, 62.5 mW, 0402 [1005 Metric], Thick Film, General Purpose"
			(at 81.28 52.07 0)
			(effects
				(font
					(size 1.27 1.27)
				)
				(hide yes)
			)
		)
		(property "Manufacturer" "Bourns"
			(at 58.42 72.39 0)
			(effects
				(font
					(size 1.27 1.27)
					(thickness 0.15)
				)
				(justify left bottom)
				(hide yes)
			)
		)
		(property "MPN" "CR0402-FX-4701GLF"
			(at 60.96 72.39 0)
			(effects
				(font
					(size 1.27 1.27)
					(thickness 0.15)
				)
				(justify left bottom)
				(hide yes)
			)
		)
		(property "Val" "4k7"
			(at 82.55 55.88 90)
			(effects
				(font
					(size 1.27 1.27)
					(thickness 0.15)
				)
				(justify left)
			)
		)
		(property "License" "Apache-2.0"
			(at 55.88 72.39 0)
			(effects
				(font
					(size 1.27 1.27)
					(thickness 0.15)
				)
				(justify left bottom)
				(hide yes)
			)
		)
		(property "Author" "Antmicro"
			(at 53.34 72.39 0)
			(effects
				(font
					(size 1.27 1.27)
					(thickness 0.15)
				)
				(justify left bottom)
				(hide yes)
			)
		)
		(property "Tolerance" "1%"
			(at 71.12 72.39 0)
			(effects
				(font
					(size 1.27 1.27)
				)
				(justify left bottom)
				(hide yes)
			)
		)
		(pin "1"
		)
		(pin "2"
		)
		(instances
			(project "artix-dc-scm"
				(path ""
					(reference "R24")
					(unit 1)
				)
			)
		)
	)
	(symbol
		(lib_id "antmicroResistors0402:R_1k_0402")
		(at 73.66 52.07 270)
		(unit 1)
		(exclude_from_sim no)
		(in_bom yes)
		(on_board yes)
		(dnp no)
		(property "Reference" "R28"
			(at 74.93 53.34 90)
			(effects
				(font
					(size 1.27 1.27)
				)
				(justify left)
			)
		)
		(property "Value" "R_1k_0402"
			(at 60.96 72.39 0)
			(effects
				(font
					(size 1.27 1.27)
					(thickness 0.15)
				)
				(justify left bottom)
				(hide yes)
			)
		)
		(property "Footprint" "antmicro-footprints:R_0402_1005Metric"
			(at 58.42 72.39 0)
			(effects
				(font
					(size 1.27 1.27)
					(thickness 0.15)
				)
				(justify left bottom)
				(hide yes)
			)
		)
		(property "Datasheet" "https://www.bourns.com/docs/product-datasheets/cr.pdf"
			(at 55.88 72.39 0)
			(effects
				(font
					(size 1.27 1.27)
					(thickness 0.15)
				)
				(justify left bottom)
				(hide yes)
			)
		)
		(property "Description" "SMD Chip Resistor, 1 kohm, ± 1%, 63 mW, 0402 [1005 Metric], Thick Film, General Purpose"
			(at 73.66 52.07 0)
			(effects
				(font
					(size 1.27 1.27)
				)
				(hide yes)
			)
		)
		(property "Manufacturer" "Bourns"
			(at 50.8 72.39 0)
			(effects
				(font
					(size 1.27 1.27)
					(thickness 0.15)
				)
				(justify left bottom)
				(hide yes)
			)
		)
		(property "MPN" "CR0402-FX-1001GLF"
			(at 53.34 72.39 0)
			(effects
				(font
					(size 1.27 1.27)
					(thickness 0.15)
				)
				(justify left bottom)
				(hide yes)
			)
		)
		(property "Val" "1k"
			(at 74.93 55.88 90)
			(effects
				(font
					(size 1.27 1.27)
					(thickness 0.15)
				)
				(justify left)
			)
		)
		(property "License" "Apache-2.0"
			(at 48.26 72.39 0)
			(effects
				(font
					(size 1.27 1.27)
					(thickness 0.15)
				)
				(justify left bottom)
				(hide yes)
			)
		)
		(property "Author" "Antmicro"
			(at 45.72 72.39 0)
			(effects
				(font
					(size 1.27 1.27)
					(thickness 0.15)
				)
				(justify left bottom)
				(hide yes)
			)
		)
		(property "Tolerance" "1%"
			(at 63.5 72.39 0)
			(effects
				(font
					(size 1.27 1.27)
				)
				(justify left bottom)
				(hide yes)
			)
		)
		(pin "1"
		)
		(pin "2"
		)
		(instances
			(project "artix-dc-scm"
				(path ""
					(reference "R28")
					(unit 1)
				)
			)
		)
	)
	(symbol
		(lib_id "antmicroResistors0402:R_10k_0402")
		(at 50.8 57.15 90)
		(unit 1)
		(exclude_from_sim no)
		(in_bom yes)
		(on_board yes)
		(dnp no)
		(property "Reference" "R32"
			(at 52.07 53.34 90)
			(effects
				(font
					(size 1.27 1.27)
				)
				(justify right)
			)
		)
		(property "Value" "R_10k_0402"
			(at 63.5 36.83 0)
			(effects
				(font
					(size 1.27 1.27)
					(thickness 0.15)
				)
				(justify left bottom)
				(hide yes)
			)
		)
		(property "Footprint" "antmicro-footprints:R_0402_1005Metric"
			(at 66.04 36.83 0)
			(effects
				(font
					(size 1.27 1.27)
					(thickness 0.15)
				)
				(justify left bottom)
				(hide yes)
			)
		)
		(property "Datasheet" "https://www.bourns.com/docs/product-datasheets/cr.pdf"
			(at 68.58 36.83 0)
			(effects
				(font
					(size 1.27 1.27)
					(thickness 0.15)
				)
				(justify left bottom)
				(hide yes)
			)
		)
		(property "Description" "SMD Chip Resistor, 10 kohm, ± 1%, 62.5 mW, 0402 [1005 Metric], Thick Film, General Purpose"
			(at 50.8 57.15 0)
			(effects
				(font
					(size 1.27 1.27)
				)
				(hide yes)
			)
		)
		(property "Manufacturer" "Bourns"
			(at 73.66 36.83 0)
			(effects
				(font
					(size 1.27 1.27)
					(thickness 0.15)
				)
				(justify left bottom)
				(hide yes)
			)
		)
		(property "MPN" "CR0402-FX-1002GLF"
			(at 71.12 36.83 0)
			(effects
				(font
					(size 1.27 1.27)
					(thickness 0.15)
				)
				(justify left bottom)
				(hide yes)
			)
		)
		(property "Val" "10k"
			(at 52.07 55.88 90)
			(effects
				(font
					(size 1.27 1.27)
					(thickness 0.15)
				)
				(justify right)
			)
		)
		(property "License" "Apache-2.0"
			(at 76.2 36.83 0)
			(effects
				(font
					(size 1.27 1.27)
					(thickness 0.15)
				)
				(justify left bottom)
				(hide yes)
			)
		)
		(property "Author" "Antmicro"
			(at 78.74 36.83 0)
			(effects
				(font
					(size 1.27 1.27)
					(thickness 0.15)
				)
				(justify left bottom)
				(hide yes)
			)
		)
		(property "Tolerance" "1%"
			(at 60.96 36.83 0)
			(effects
				(font
					(size 1.27 1.27)
				)
				(justify left bottom)
				(hide yes)
			)
		)
		(pin "1"
		)
		(pin "2"
		)
		(instances
			(project "artix-dc-scm"
				(path ""
					(reference "R32")
					(unit 1)
				)
			)
		)
	)
	(symbol
		(lib_id "antmicroResistors0402:R_10k_0402")
		(at 66.04 57.15 90)
		(unit 1)
		(exclude_from_sim no)
		(in_bom yes)
		(on_board yes)
		(dnp no)
		(property "Reference" "R40"
			(at 67.31 53.34 90)
			(effects
				(font
					(size 1.27 1.27)
				)
				(justify right)
			)
		)
		(property "Value" "R_10k_0402"
			(at 78.74 36.83 0)
			(effects
				(font
					(size 1.27 1.27)
					(thickness 0.15)
				)
				(justify left bottom)
				(hide yes)
			)
		)
		(property "Footprint" "antmicro-footprints:R_0402_1005Metric"
			(at 81.28 36.83 0)
			(effects
				(font
					(size 1.27 1.27)
					(thickness 0.15)
				)
				(justify left bottom)
				(hide yes)
			)
		)
		(property "Datasheet" "https://www.bourns.com/docs/product-datasheets/cr.pdf"
			(at 83.82 36.83 0)
			(effects
				(font
					(size 1.27 1.27)
					(thickness 0.15)
				)
				(justify left bottom)
				(hide yes)
			)
		)
		(property "Description" "SMD Chip Resistor, 10 kohm, ± 1%, 62.5 mW, 0402 [1005 Metric], Thick Film, General Purpose"
			(at 66.04 57.15 0)
			(effects
				(font
					(size 1.27 1.27)
				)
				(hide yes)
			)
		)
		(property "Manufacturer" "Bourns"
			(at 88.9 36.83 0)
			(effects
				(font
					(size 1.27 1.27)
					(thickness 0.15)
				)
				(justify left bottom)
				(hide yes)
			)
		)
		(property "MPN" "CR0402-FX-1002GLF"
			(at 86.36 36.83 0)
			(effects
				(font
					(size 1.27 1.27)
					(thickness 0.15)
				)
				(justify left bottom)
				(hide yes)
			)
		)
		(property "Val" "10k"
			(at 67.31 55.88 90)
			(effects
				(font
					(size 1.27 1.27)
					(thickness 0.15)
				)
				(justify right)
			)
		)
		(property "License" "Apache-2.0"
			(at 91.44 36.83 0)
			(effects
				(font
					(size 1.27 1.27)
					(thickness 0.15)
				)
				(justify left bottom)
				(hide yes)
			)
		)
		(property "Author" "Antmicro"
			(at 93.98 36.83 0)
			(effects
				(font
					(size 1.27 1.27)
					(thickness 0.15)
				)
				(justify left bottom)
				(hide yes)
			)
		)
		(property "Tolerance" "1%"
			(at 76.2 36.83 0)
			(effects
				(font
					(size 1.27 1.27)
				)
				(justify left bottom)
				(hide yes)
			)
		)
		(pin "1"
		)
		(pin "2"
		)
		(instances
			(project "artix-dc-scm"
				(path ""
					(reference "R40")
					(unit 1)
				)
			)
		)
	)
	(symbol
		(lib_id "antmicroResistors0402:R_10k_0402")
		(at 43.18 57.15 270)
		(mirror x)
		(unit 1)
		(exclude_from_sim no)
		(in_bom yes)
		(on_board yes)
		(dnp no)
		(property "Reference" "R44"
			(at 44.45 53.34 90)
			(effects
				(font
					(size 1.27 1.27)
				)
				(justify left)
			)
		)
		(property "Value" "R_10k_0402"
			(at 30.48 36.83 0)
			(effects
				(font
					(size 1.27 1.27)
					(thickness 0.15)
				)
				(justify left bottom)
				(hide yes)
			)
		)
		(property "Footprint" "antmicro-footprints:R_0402_1005Metric"
			(at 27.94 36.83 0)
			(effects
				(font
					(size 1.27 1.27)
					(thickness 0.15)
				)
				(justify left bottom)
				(hide yes)
			)
		)
		(property "Datasheet" "https://www.bourns.com/docs/product-datasheets/cr.pdf"
			(at 25.4 36.83 0)
			(effects
				(font
					(size 1.27 1.27)
					(thickness 0.15)
				)
				(justify left bottom)
				(hide yes)
			)
		)
		(property "Description" "SMD Chip Resistor, 10 kohm, ± 1%, 62.5 mW, 0402 [1005 Metric], Thick Film, General Purpose"
			(at 43.18 57.15 0)
			(effects
				(font
					(size 1.27 1.27)
				)
				(hide yes)
			)
		)
		(property "Manufacturer" "Bourns"
			(at 20.32 36.83 0)
			(effects
				(font
					(size 1.27 1.27)
					(thickness 0.15)
				)
				(justify left bottom)
				(hide yes)
			)
		)
		(property "MPN" "CR0402-FX-1002GLF"
			(at 22.86 36.83 0)
			(effects
				(font
					(size 1.27 1.27)
					(thickness 0.15)
				)
				(justify left bottom)
				(hide yes)
			)
		)
		(property "Val" "10k"
			(at 44.45 55.88 90)
			(effects
				(font
					(size 1.27 1.27)
					(thickness 0.15)
				)
				(justify left)
			)
		)
		(property "License" "Apache-2.0"
			(at 17.78 36.83 0)
			(effects
				(font
					(size 1.27 1.27)
					(thickness 0.15)
				)
				(justify left bottom)
				(hide yes)
			)
		)
		(property "Author" "Antmicro"
			(at 15.24 36.83 0)
			(effects
				(font
					(size 1.27 1.27)
					(thickness 0.15)
				)
				(justify left bottom)
				(hide yes)
			)
		)
		(property "Tolerance" "1%"
			(at 33.02 36.83 0)
			(effects
				(font
					(size 1.27 1.27)
				)
				(justify left bottom)
				(hide yes)
			)
		)
		(pin "1"
		)
		(pin "2"
		)
		(instances
			(project "artix-dc-scm"
				(path ""
					(reference "R44")
					(unit 1)
				)
			)
		)
	)
	(symbol
		(lib_id "antmicroCapacitors0402:C_470n_0402")
		(at 113.03 68.58 90)
		(unit 1)
		(exclude_from_sim no)
		(in_bom yes)
		(on_board yes)
		(dnp no)
		(property "Reference" "C38"
			(at 113.665 64.135 90)
			(effects
				(font
					(size 1.27 1.27)
				)
				(justify right)
			)
		)
		(property "Value" "C_470n_0402"
			(at 123.19 48.26 0)
			(effects
				(font
					(size 1.27 1.27)
					(thickness 0.15)
				)
				(justify left bottom)
				(hide yes)
			)
		)
		(property "Footprint" "antmicro-footprints:C_0402_1005Metric"
			(at 125.73 48.26 0)
			(effects
				(font
					(size 1.27 1.27)
					(thickness 0.15)
				)
				(justify left bottom)
				(hide yes)
			)
		)
		(property "Datasheet" "https://product.tdk.com/en/search/capacitor/ceramic/mlcc/info?part_no=C1005X5R1E474M050BB"
			(at 128.27 48.26 0)
			(effects
				(font
					(size 1.27 1.27)
					(thickness 0.15)
				)
				(justify left bottom)
				(hide yes)
			)
		)
		(property "Description" "SMD Multilayer Ceramic Capacitor, 0.47 µF, 25 V, 0402 [1005 Metric], ± 20%, X5R, C"
			(at 113.03 68.58 0)
			(effects
				(font
					(size 1.27 1.27)
				)
				(hide yes)
			)
		)
		(property "Manufacturer" "TDK"
			(at 133.35 48.26 0)
			(effects
				(font
					(size 1.27 1.27)
					(thickness 0.15)
				)
				(justify left bottom)
				(hide yes)
			)
		)
		(property "MPN" "C1005X5R1E474M050BB"
			(at 130.81 48.26 0)
			(effects
				(font
					(size 1.27 1.27)
					(thickness 0.15)
				)
				(justify left bottom)
				(hide yes)
			)
		)
		(property "Val" "470n"
			(at 113.665 67.945 90)
			(effects
				(font
					(size 1.27 1.27)
					(thickness 0.15)
				)
				(justify right)
			)
		)
		(property "License" "Apache-2.0"
			(at 135.89 48.26 0)
			(effects
				(font
					(size 1.27 1.27)
					(thickness 0.15)
				)
				(justify left bottom)
				(hide yes)
			)
		)
		(property "Author" "Antmicro"
			(at 138.43 48.26 0)
			(effects
				(font
					(size 1.27 1.27)
					(thickness 0.15)
				)
				(justify left bottom)
				(hide yes)
			)
		)
		(property "Voltage" ""
			(at 140.97 48.26 0)
			(effects
				(font
					(size 1.27 1.27)
				)
				(justify left bottom)
				(hide yes)
			)
		)
		(property "Dielectric" ""
			(at 143.51 48.26 0)
			(effects
				(font
					(size 1.27 1.27)
				)
				(justify left bottom)
				(hide yes)
			)
		)
		(pin "1"
		)
		(pin "2"
		)
		(instances
			(project "artix-dc-scm"
				(path ""
					(reference "C38")
					(unit 1)
				)
			)
		)
	)
	(symbol
		(lib_id "antmicroResistors0402:R_10k_0402")
		(at 58.42 57.15 90)
		(unit 1)
		(exclude_from_sim no)
		(in_bom yes)
		(on_board yes)
		(dnp no)
		(property "Reference" "R36"
			(at 59.69 53.34 90)
			(effects
				(font
					(size 1.27 1.27)
				)
				(justify right)
			)
		)
		(property "Value" "R_10k_0402"
			(at 71.12 36.83 0)
			(effects
				(font
					(size 1.27 1.27)
					(thickness 0.15)
				)
				(justify left bottom)
				(hide yes)
			)
		)
		(property "Footprint" "antmicro-footprints:R_0402_1005Metric"
			(at 73.66 36.83 0)
			(effects
				(font
					(size 1.27 1.27)
					(thickness 0.15)
				)
				(justify left bottom)
				(hide yes)
			)
		)
		(property "Datasheet" "https://www.bourns.com/docs/product-datasheets/cr.pdf"
			(at 76.2 36.83 0)
			(effects
				(font
					(size 1.27 1.27)
					(thickness 0.15)
				)
				(justify left bottom)
				(hide yes)
			)
		)
		(property "Description" "SMD Chip Resistor, 10 kohm, ± 1%, 62.5 mW, 0402 [1005 Metric], Thick Film, General Purpose"
			(at 58.42 57.15 0)
			(effects
				(font
					(size 1.27 1.27)
				)
				(hide yes)
			)
		)
		(property "Manufacturer" "Bourns"
			(at 81.28 36.83 0)
			(effects
				(font
					(size 1.27 1.27)
					(thickness 0.15)
				)
				(justify left bottom)
				(hide yes)
			)
		)
		(property "MPN" "CR0402-FX-1002GLF"
			(at 78.74 36.83 0)
			(effects
				(font
					(size 1.27 1.27)
					(thickness 0.15)
				)
				(justify left bottom)
				(hide yes)
			)
		)
		(property "Val" "10k"
			(at 59.69 55.88 90)
			(effects
				(font
					(size 1.27 1.27)
					(thickness 0.15)
				)
				(justify right)
			)
		)
		(property "License" "Apache-2.0"
			(at 83.82 36.83 0)
			(effects
				(font
					(size 1.27 1.27)
					(thickness 0.15)
				)
				(justify left bottom)
				(hide yes)
			)
		)
		(property "Author" "Antmicro"
			(at 86.36 36.83 0)
			(effects
				(font
					(size 1.27 1.27)
					(thickness 0.15)
				)
				(justify left bottom)
				(hide yes)
			)
		)
		(property "Tolerance" "1%"
			(at 68.58 36.83 0)
			(effects
				(font
					(size 1.27 1.27)
				)
				(justify left bottom)
				(hide yes)
			)
		)
		(pin "1"
		)
		(pin "2"
		)
		(instances
			(project "artix-dc-scm"
				(path ""
					(reference "R36")
					(unit 1)
				)
			)
		)
	)
	(symbol
		(lib_id "antmicroMemory:W25Q32JW_SOIC-8")
		(at 92.71 59.69 0)
		(unit 1)
		(exclude_from_sim no)
		(in_bom yes)
		(on_board yes)
		(dnp no)
		(fields_autoplaced yes)
		(property "Reference" "U5"
			(at 102.235 52.07 0)
			(effects
				(font
					(size 1.27 1.27)
				)
			)
		)
		(property "Value" "W25Q32JW_SOIC-8"
			(at 102.235 54.61 0)
			(effects
				(font
					(size 1.27 1.27)
					(thickness 0.15)
				)
				(hide yes)
			)
		)
		(property "Footprint" "antmicro-footprints:SOIC-8_5.3x5.3x2mm_P1.27mm"
			(at 125.73 68.58 0)
			(effects
				(font
					(size 1.27 1.27)
					(thickness 0.15)
				)
				(justify left bottom)
				(hide yes)
			)
		)
		(property "Datasheet" "https://www.mouser.com/datasheet/2/949/w25q32jw_spi_revf_09042018-1489621.pdf"
			(at 125.73 71.12 0)
			(effects
				(font
					(size 1.27 1.27)
					(thickness 0.15)
				)
				(justify left bottom)
				(hide yes)
			)
		)
		(property "Description" "FLASH - NOR Memory IC 32Mbit SPI - Quad I/O 133 MHz 8-SOIC"
			(at 92.71 59.69 0)
			(effects
				(font
					(size 1.27 1.27)
				)
				(hide yes)
			)
		)
		(property "MPN" "W25Q32JWSSIQ"
			(at 102.235 54.61 0)
			(effects
				(font
					(size 1.27 1.27)
					(thickness 0.15)
				)
			)
		)
		(property "Manufacturer" "Winbond"
			(at 125.73 76.2 0)
			(effects
				(font
					(size 1.27 1.27)
					(thickness 0.15)
				)
				(justify left bottom)
				(hide yes)
			)
		)
		(property "Author" "Antmicro"
			(at 125.73 78.74 0)
			(effects
				(font
					(size 1.27 1.27)
					(thickness 0.15)
				)
				(justify left bottom)
				(hide yes)
			)
		)
		(property "License" "Apache-2.0"
			(at 125.73 81.28 0)
			(effects
				(font
					(size 1.27 1.27)
					(thickness 0.15)
				)
				(justify left bottom)
				(hide yes)
			)
		)
		(pin "1"
		)
		(pin "2"
		)
		(pin "3"
		)
		(pin "4"
		)
		(pin "5"
		)
		(pin "6"
		)
		(pin "7"
		)
		(pin "8"
		)
		(instances
			(project "artix-dc-scm"
				(path ""
					(reference "U5")
					(unit 1)
				)
			)
		)
	)
	(symbol
		(lib_id "antmicropower:GND")
		(at 308.61 144.78 0)
		(unit 1)
		(exclude_from_sim no)
		(in_bom yes)
		(on_board yes)
		(dnp no)
		(property "Reference" "#PWR024"
			(at 308.61 151.13 0)
			(effects
				(font
					(size 1.27 1.27)
				)
				(hide yes)
			)
		)
		(property "Value" "GND"
			(at 308.61 148.59 0)
			(effects
				(font
					(size 1.27 1.27)
				)
			)
		)
		(property "Footprint" ""
			(at 308.61 144.78 0)
			(effects
				(font
					(size 1.27 1.27)
				)
				(hide yes)
			)
		)
		(property "Datasheet" ""
			(at 308.61 144.78 0)
			(effects
				(font
					(size 1.27 1.27)
				)
				(hide yes)
			)
		)
		(property "Description" ""
			(at 308.61 144.78 0)
			(effects
				(font
					(size 1.27 1.27)
				)
				(hide yes)
			)
		)
		(property "Author" "Antmicro"
			(at 317.5 152.4 0)
			(effects
				(font
					(size 1.27 1.27)
					(thickness 0.15)
				)
				(justify left bottom)
				(hide yes)
			)
		)
		(property "License" "Apache-2.0"
			(at 317.5 154.94 0)
			(effects
				(font
					(size 1.27 1.27)
					(thickness 0.15)
				)
				(justify left bottom)
				(hide yes)
			)
		)
		(pin "1"
		)
		(instances
			(project "artix-dc-scm"
				(path ""
					(reference "#PWR024")
					(unit 1)
				)
			)
		)
	)
	(symbol
		(lib_id "antmicropower:GND")
		(at 325.12 144.78 0)
		(unit 1)
		(exclude_from_sim no)
		(in_bom yes)
		(on_board yes)
		(dnp no)
		(property "Reference" "#PWR025"
			(at 325.12 151.13 0)
			(effects
				(font
					(size 1.27 1.27)
				)
				(hide yes)
			)
		)
		(property "Value" "GND"
			(at 325.12 148.59 0)
			(effects
				(font
					(size 1.27 1.27)
				)
			)
		)
		(property "Footprint" ""
			(at 325.12 144.78 0)
			(effects
				(font
					(size 1.27 1.27)
				)
				(hide yes)
			)
		)
		(property "Datasheet" ""
			(at 325.12 144.78 0)
			(effects
				(font
					(size 1.27 1.27)
				)
				(hide yes)
			)
		)
		(property "Description" ""
			(at 325.12 144.78 0)
			(effects
				(font
					(size 1.27 1.27)
				)
				(hide yes)
			)
		)
		(property "Author" "Antmicro"
			(at 334.01 152.4 0)
			(effects
				(font
					(size 1.27 1.27)
					(thickness 0.15)
				)
				(justify left bottom)
				(hide yes)
			)
		)
		(property "License" "Apache-2.0"
			(at 334.01 154.94 0)
			(effects
				(font
					(size 1.27 1.27)
					(thickness 0.15)
				)
				(justify left bottom)
				(hide yes)
			)
		)
		(pin "1"
		)
		(instances
			(project "artix-dc-scm"
				(path ""
					(reference "#PWR025")
					(unit 1)
				)
			)
		)
	)
	(symbol
		(lib_id "antmicroResistors0402:R_4k7_0402")
		(at 81.28 96.52 270)
		(unit 1)
		(exclude_from_sim no)
		(in_bom yes)
		(on_board yes)
		(dnp no)
		(property "Reference" "R23"
			(at 82.55 97.79 90)
			(effects
				(font
					(size 1.27 1.27)
				)
				(justify left)
			)
		)
		(property "Value" "R_4k7_0402"
			(at 68.58 116.84 0)
			(effects
				(font
					(size 1.27 1.27)
					(thickness 0.15)
				)
				(justify left bottom)
				(hide yes)
			)
		)
		(property "Footprint" "antmicro-footprints:R_0402_1005Metric"
			(at 66.04 116.84 0)
			(effects
				(font
					(size 1.27 1.27)
					(thickness 0.15)
				)
				(justify left bottom)
				(hide yes)
			)
		)
		(property "Datasheet" "https://www.bourns.com/docs/product-datasheets/cr.pdf"
			(at 63.5 116.84 0)
			(effects
				(font
					(size 1.27 1.27)
					(thickness 0.15)
				)
				(justify left bottom)
				(hide yes)
			)
		)
		(property "Description" "SMD Chip Resistor, 4.7 kohm, ± 1%, 62.5 mW, 0402 [1005 Metric], Thick Film, General Purpose"
			(at 81.28 96.52 0)
			(effects
				(font
					(size 1.27 1.27)
				)
				(hide yes)
			)
		)
		(property "Manufacturer" "Bourns"
			(at 58.42 116.84 0)
			(effects
				(font
					(size 1.27 1.27)
					(thickness 0.15)
				)
				(justify left bottom)
				(hide yes)
			)
		)
		(property "MPN" "CR0402-FX-4701GLF"
			(at 60.96 116.84 0)
			(effects
				(font
					(size 1.27 1.27)
					(thickness 0.15)
				)
				(justify left bottom)
				(hide yes)
			)
		)
		(property "Val" "4k7"
			(at 82.55 100.33 90)
			(effects
				(font
					(size 1.27 1.27)
					(thickness 0.15)
				)
				(justify left)
			)
		)
		(property "License" "Apache-2.0"
			(at 55.88 116.84 0)
			(effects
				(font
					(size 1.27 1.27)
					(thickness 0.15)
				)
				(justify left bottom)
				(hide yes)
			)
		)
		(property "Author" "Antmicro"
			(at 53.34 116.84 0)
			(effects
				(font
					(size 1.27 1.27)
					(thickness 0.15)
				)
				(justify left bottom)
				(hide yes)
			)
		)
		(property "Tolerance" "1%"
			(at 71.12 116.84 0)
			(effects
				(font
					(size 1.27 1.27)
				)
				(justify left bottom)
				(hide yes)
			)
		)
		(pin "1"
		)
		(pin "2"
		)
		(instances
			(project "artix-dc-scm"
				(path ""
					(reference "R23")
					(unit 1)
				)
			)
		)
	)
	(symbol
		(lib_id "antmicroResistors0402:R_1k_0402")
		(at 73.66 96.52 270)
		(unit 1)
		(exclude_from_sim no)
		(in_bom yes)
		(on_board yes)
		(dnp no)
		(property "Reference" "R27"
			(at 74.93 97.79 90)
			(effects
				(font
					(size 1.27 1.27)
				)
				(justify left)
			)
		)
		(property "Value" "R_1k_0402"
			(at 60.96 116.84 0)
			(effects
				(font
					(size 1.27 1.27)
					(thickness 0.15)
				)
				(justify left bottom)
				(hide yes)
			)
		)
		(property "Footprint" "antmicro-footprints:R_0402_1005Metric"
			(at 58.42 116.84 0)
			(effects
				(font
					(size 1.27 1.27)
					(thickness 0.15)
				)
				(justify left bottom)
				(hide yes)
			)
		)
		(property "Datasheet" "https://www.bourns.com/docs/product-datasheets/cr.pdf"
			(at 55.88 116.84 0)
			(effects
				(font
					(size 1.27 1.27)
					(thickness 0.15)
				)
				(justify left bottom)
				(hide yes)
			)
		)
		(property "Description" "SMD Chip Resistor, 1 kohm, ± 1%, 63 mW, 0402 [1005 Metric], Thick Film, General Purpose"
			(at 73.66 96.52 0)
			(effects
				(font
					(size 1.27 1.27)
				)
				(hide yes)
			)
		)
		(property "Manufacturer" "Bourns"
			(at 50.8 116.84 0)
			(effects
				(font
					(size 1.27 1.27)
					(thickness 0.15)
				)
				(justify left bottom)
				(hide yes)
			)
		)
		(property "MPN" "CR0402-FX-1001GLF"
			(at 53.34 116.84 0)
			(effects
				(font
					(size 1.27 1.27)
					(thickness 0.15)
				)
				(justify left bottom)
				(hide yes)
			)
		)
		(property "Val" "1k"
			(at 74.93 100.33 90)
			(effects
				(font
					(size 1.27 1.27)
					(thickness 0.15)
				)
				(justify left)
			)
		)
		(property "License" "Apache-2.0"
			(at 48.26 116.84 0)
			(effects
				(font
					(size 1.27 1.27)
					(thickness 0.15)
				)
				(justify left bottom)
				(hide yes)
			)
		)
		(property "Author" "Antmicro"
			(at 45.72 116.84 0)
			(effects
				(font
					(size 1.27 1.27)
					(thickness 0.15)
				)
				(justify left bottom)
				(hide yes)
			)
		)
		(property "Tolerance" "1%"
			(at 63.5 116.84 0)
			(effects
				(font
					(size 1.27 1.27)
				)
				(justify left bottom)
				(hide yes)
			)
		)
		(pin "1"
		)
		(pin "2"
		)
		(instances
			(project "artix-dc-scm"
				(path ""
					(reference "R27")
					(unit 1)
				)
			)
		)
	)
	(symbol
		(lib_id "antmicroResistors0402:R_10k_0402")
		(at 50.8 101.6 90)
		(unit 1)
		(exclude_from_sim no)
		(in_bom yes)
		(on_board yes)
		(dnp no)
		(property "Reference" "R31"
			(at 52.07 97.79 90)
			(effects
				(font
					(size 1.27 1.27)
				)
				(justify right)
			)
		)
		(property "Value" "R_10k_0402"
			(at 63.5 81.28 0)
			(effects
				(font
					(size 1.27 1.27)
					(thickness 0.15)
				)
				(justify left bottom)
				(hide yes)
			)
		)
		(property "Footprint" "antmicro-footprints:R_0402_1005Metric"
			(at 66.04 81.28 0)
			(effects
				(font
					(size 1.27 1.27)
					(thickness 0.15)
				)
				(justify left bottom)
				(hide yes)
			)
		)
		(property "Datasheet" "https://www.bourns.com/docs/product-datasheets/cr.pdf"
			(at 68.58 81.28 0)
			(effects
				(font
					(size 1.27 1.27)
					(thickness 0.15)
				)
				(justify left bottom)
				(hide yes)
			)
		)
		(property "Description" "SMD Chip Resistor, 10 kohm, ± 1%, 62.5 mW, 0402 [1005 Metric], Thick Film, General Purpose"
			(at 50.8 101.6 0)
			(effects
				(font
					(size 1.27 1.27)
				)
				(hide yes)
			)
		)
		(property "Manufacturer" "Bourns"
			(at 73.66 81.28 0)
			(effects
				(font
					(size 1.27 1.27)
					(thickness 0.15)
				)
				(justify left bottom)
				(hide yes)
			)
		)
		(property "MPN" "CR0402-FX-1002GLF"
			(at 71.12 81.28 0)
			(effects
				(font
					(size 1.27 1.27)
					(thickness 0.15)
				)
				(justify left bottom)
				(hide yes)
			)
		)
		(property "Val" "10k"
			(at 52.07 100.33 90)
			(effects
				(font
					(size 1.27 1.27)
					(thickness 0.15)
				)
				(justify right)
			)
		)
		(property "License" "Apache-2.0"
			(at 76.2 81.28 0)
			(effects
				(font
					(size 1.27 1.27)
					(thickness 0.15)
				)
				(justify left bottom)
				(hide yes)
			)
		)
		(property "Author" "Antmicro"
			(at 78.74 81.28 0)
			(effects
				(font
					(size 1.27 1.27)
					(thickness 0.15)
				)
				(justify left bottom)
				(hide yes)
			)
		)
		(property "Tolerance" "1%"
			(at 60.96 81.28 0)
			(effects
				(font
					(size 1.27 1.27)
				)
				(justify left bottom)
				(hide yes)
			)
		)
		(pin "1"
		)
		(pin "2"
		)
		(instances
			(project "artix-dc-scm"
				(path ""
					(reference "R31")
					(unit 1)
				)
			)
		)
	)
	(symbol
		(lib_id "antmicroResistors0402:R_10k_0402")
		(at 66.04 101.6 90)
		(unit 1)
		(exclude_from_sim no)
		(in_bom yes)
		(on_board yes)
		(dnp no)
		(property "Reference" "R39"
			(at 67.31 97.79 90)
			(effects
				(font
					(size 1.27 1.27)
				)
				(justify right)
			)
		)
		(property "Value" "R_10k_0402"
			(at 78.74 81.28 0)
			(effects
				(font
					(size 1.27 1.27)
					(thickness 0.15)
				)
				(justify left bottom)
				(hide yes)
			)
		)
		(property "Footprint" "antmicro-footprints:R_0402_1005Metric"
			(at 81.28 81.28 0)
			(effects
				(font
					(size 1.27 1.27)
					(thickness 0.15)
				)
				(justify left bottom)
				(hide yes)
			)
		)
		(property "Datasheet" "https://www.bourns.com/docs/product-datasheets/cr.pdf"
			(at 83.82 81.28 0)
			(effects
				(font
					(size 1.27 1.27)
					(thickness 0.15)
				)
				(justify left bottom)
				(hide yes)
			)
		)
		(property "Description" "SMD Chip Resistor, 10 kohm, ± 1%, 62.5 mW, 0402 [1005 Metric], Thick Film, General Purpose"
			(at 66.04 101.6 0)
			(effects
				(font
					(size 1.27 1.27)
				)
				(hide yes)
			)
		)
		(property "Manufacturer" "Bourns"
			(at 88.9 81.28 0)
			(effects
				(font
					(size 1.27 1.27)
					(thickness 0.15)
				)
				(justify left bottom)
				(hide yes)
			)
		)
		(property "MPN" "CR0402-FX-1002GLF"
			(at 86.36 81.28 0)
			(effects
				(font
					(size 1.27 1.27)
					(thickness 0.15)
				)
				(justify left bottom)
				(hide yes)
			)
		)
		(property "Val" "10k"
			(at 67.31 100.33 90)
			(effects
				(font
					(size 1.27 1.27)
					(thickness 0.15)
				)
				(justify right)
			)
		)
		(property "License" "Apache-2.0"
			(at 91.44 81.28 0)
			(effects
				(font
					(size 1.27 1.27)
					(thickness 0.15)
				)
				(justify left bottom)
				(hide yes)
			)
		)
		(property "Author" "Antmicro"
			(at 93.98 81.28 0)
			(effects
				(font
					(size 1.27 1.27)
					(thickness 0.15)
				)
				(justify left bottom)
				(hide yes)
			)
		)
		(property "Tolerance" "1%"
			(at 76.2 81.28 0)
			(effects
				(font
					(size 1.27 1.27)
				)
				(justify left bottom)
				(hide yes)
			)
		)
		(pin "1"
		)
		(pin "2"
		)
		(instances
			(project "artix-dc-scm"
				(path ""
					(reference "R39")
					(unit 1)
				)
			)
		)
	)
	(symbol
		(lib_id "antmicroResistors0402:R_10k_0402")
		(at 43.18 101.6 270)
		(mirror x)
		(unit 1)
		(exclude_from_sim no)
		(in_bom yes)
		(on_board yes)
		(dnp no)
		(property "Reference" "R43"
			(at 44.45 97.79 90)
			(effects
				(font
					(size 1.27 1.27)
				)
				(justify left)
			)
		)
		(property "Value" "R_10k_0402"
			(at 30.48 81.28 0)
			(effects
				(font
					(size 1.27 1.27)
					(thickness 0.15)
				)
				(justify left bottom)
				(hide yes)
			)
		)
		(property "Footprint" "antmicro-footprints:R_0402_1005Metric"
			(at 27.94 81.28 0)
			(effects
				(font
					(size 1.27 1.27)
					(thickness 0.15)
				)
				(justify left bottom)
				(hide yes)
			)
		)
		(property "Datasheet" "https://www.bourns.com/docs/product-datasheets/cr.pdf"
			(at 25.4 81.28 0)
			(effects
				(font
					(size 1.27 1.27)
					(thickness 0.15)
				)
				(justify left bottom)
				(hide yes)
			)
		)
		(property "Description" "SMD Chip Resistor, 10 kohm, ± 1%, 62.5 mW, 0402 [1005 Metric], Thick Film, General Purpose"
			(at 43.18 101.6 0)
			(effects
				(font
					(size 1.27 1.27)
				)
				(hide yes)
			)
		)
		(property "Manufacturer" "Bourns"
			(at 20.32 81.28 0)
			(effects
				(font
					(size 1.27 1.27)
					(thickness 0.15)
				)
				(justify left bottom)
				(hide yes)
			)
		)
		(property "MPN" "CR0402-FX-1002GLF"
			(at 22.86 81.28 0)
			(effects
				(font
					(size 1.27 1.27)
					(thickness 0.15)
				)
				(justify left bottom)
				(hide yes)
			)
		)
		(property "Val" "10k"
			(at 44.45 100.33 90)
			(effects
				(font
					(size 1.27 1.27)
					(thickness 0.15)
				)
				(justify left)
			)
		)
		(property "License" "Apache-2.0"
			(at 17.78 81.28 0)
			(effects
				(font
					(size 1.27 1.27)
					(thickness 0.15)
				)
				(justify left bottom)
				(hide yes)
			)
		)
		(property "Author" "Antmicro"
			(at 15.24 81.28 0)
			(effects
				(font
					(size 1.27 1.27)
					(thickness 0.15)
				)
				(justify left bottom)
				(hide yes)
			)
		)
		(property "Tolerance" "1%"
			(at 33.02 81.28 0)
			(effects
				(font
					(size 1.27 1.27)
				)
				(justify left bottom)
				(hide yes)
			)
		)
		(pin "1"
		)
		(pin "2"
		)
		(instances
			(project "artix-dc-scm"
				(path ""
					(reference "R43")
					(unit 1)
				)
			)
		)
	)
	(symbol
		(lib_id "antmicroCapacitors0402:C_470n_0402")
		(at 113.03 113.03 90)
		(unit 1)
		(exclude_from_sim no)
		(in_bom yes)
		(on_board yes)
		(dnp no)
		(property "Reference" "C37"
			(at 113.665 108.585 90)
			(effects
				(font
					(size 1.27 1.27)
				)
				(justify right)
			)
		)
		(property "Value" "C_470n_0402"
			(at 123.19 92.71 0)
			(effects
				(font
					(size 1.27 1.27)
					(thickness 0.15)
				)
				(justify left bottom)
				(hide yes)
			)
		)
		(property "Footprint" "antmicro-footprints:C_0402_1005Metric"
			(at 125.73 92.71 0)
			(effects
				(font
					(size 1.27 1.27)
					(thickness 0.15)
				)
				(justify left bottom)
				(hide yes)
			)
		)
		(property "Datasheet" "https://product.tdk.com/en/search/capacitor/ceramic/mlcc/info?part_no=C1005X5R1E474M050BB"
			(at 128.27 92.71 0)
			(effects
				(font
					(size 1.27 1.27)
					(thickness 0.15)
				)
				(justify left bottom)
				(hide yes)
			)
		)
		(property "Description" "SMD Multilayer Ceramic Capacitor, 0.47 µF, 25 V, 0402 [1005 Metric], ± 20%, X5R, C"
			(at 113.03 113.03 0)
			(effects
				(font
					(size 1.27 1.27)
				)
				(hide yes)
			)
		)
		(property "Manufacturer" "TDK"
			(at 133.35 92.71 0)
			(effects
				(font
					(size 1.27 1.27)
					(thickness 0.15)
				)
				(justify left bottom)
				(hide yes)
			)
		)
		(property "MPN" "C1005X5R1E474M050BB"
			(at 130.81 92.71 0)
			(effects
				(font
					(size 1.27 1.27)
					(thickness 0.15)
				)
				(justify left bottom)
				(hide yes)
			)
		)
		(property "Val" "470n"
			(at 113.665 112.395 90)
			(effects
				(font
					(size 1.27 1.27)
					(thickness 0.15)
				)
				(justify right)
			)
		)
		(property "License" "Apache-2.0"
			(at 135.89 92.71 0)
			(effects
				(font
					(size 1.27 1.27)
					(thickness 0.15)
				)
				(justify left bottom)
				(hide yes)
			)
		)
		(property "Author" "Antmicro"
			(at 138.43 92.71 0)
			(effects
				(font
					(size 1.27 1.27)
					(thickness 0.15)
				)
				(justify left bottom)
				(hide yes)
			)
		)
		(property "Voltage" ""
			(at 140.97 92.71 0)
			(effects
				(font
					(size 1.27 1.27)
				)
				(justify left bottom)
				(hide yes)
			)
		)
		(property "Dielectric" ""
			(at 143.51 92.71 0)
			(effects
				(font
					(size 1.27 1.27)
				)
				(justify left bottom)
				(hide yes)
			)
		)
		(pin "1"
		)
		(pin "2"
		)
		(instances
			(project "artix-dc-scm"
				(path ""
					(reference "C37")
					(unit 1)
				)
			)
		)
	)
	(symbol
		(lib_id "antmicroResistors0402:R_10k_0402")
		(at 58.42 101.6 90)
		(unit 1)
		(exclude_from_sim no)
		(in_bom yes)
		(on_board yes)
		(dnp no)
		(property "Reference" "R35"
			(at 59.69 97.79 90)
			(effects
				(font
					(size 1.27 1.27)
				)
				(justify right)
			)
		)
		(property "Value" "R_10k_0402"
			(at 71.12 81.28 0)
			(effects
				(font
					(size 1.27 1.27)
					(thickness 0.15)
				)
				(justify left bottom)
				(hide yes)
			)
		)
		(property "Footprint" "antmicro-footprints:R_0402_1005Metric"
			(at 73.66 81.28 0)
			(effects
				(font
					(size 1.27 1.27)
					(thickness 0.15)
				)
				(justify left bottom)
				(hide yes)
			)
		)
		(property "Datasheet" "https://www.bourns.com/docs/product-datasheets/cr.pdf"
			(at 76.2 81.28 0)
			(effects
				(font
					(size 1.27 1.27)
					(thickness 0.15)
				)
				(justify left bottom)
				(hide yes)
			)
		)
		(property "Description" "SMD Chip Resistor, 10 kohm, ± 1%, 62.5 mW, 0402 [1005 Metric], Thick Film, General Purpose"
			(at 58.42 101.6 0)
			(effects
				(font
					(size 1.27 1.27)
				)
				(hide yes)
			)
		)
		(property "Manufacturer" "Bourns"
			(at 81.28 81.28 0)
			(effects
				(font
					(size 1.27 1.27)
					(thickness 0.15)
				)
				(justify left bottom)
				(hide yes)
			)
		)
		(property "MPN" "CR0402-FX-1002GLF"
			(at 78.74 81.28 0)
			(effects
				(font
					(size 1.27 1.27)
					(thickness 0.15)
				)
				(justify left bottom)
				(hide yes)
			)
		)
		(property "Val" "10k"
			(at 59.69 100.33 90)
			(effects
				(font
					(size 1.27 1.27)
					(thickness 0.15)
				)
				(justify right)
			)
		)
		(property "License" "Apache-2.0"
			(at 83.82 81.28 0)
			(effects
				(font
					(size 1.27 1.27)
					(thickness 0.15)
				)
				(justify left bottom)
				(hide yes)
			)
		)
		(property "Author" "Antmicro"
			(at 86.36 81.28 0)
			(effects
				(font
					(size 1.27 1.27)
					(thickness 0.15)
				)
				(justify left bottom)
				(hide yes)
			)
		)
		(property "Tolerance" "1%"
			(at 68.58 81.28 0)
			(effects
				(font
					(size 1.27 1.27)
				)
				(justify left bottom)
				(hide yes)
			)
		)
		(pin "1"
		)
		(pin "2"
		)
		(instances
			(project "artix-dc-scm"
				(path ""
					(reference "R35")
					(unit 1)
				)
			)
		)
	)
	(symbol
		(lib_id "antmicroMemory:W25Q32JW_SOIC-8")
		(at 92.71 104.14 0)
		(unit 1)
		(exclude_from_sim no)
		(in_bom yes)
		(on_board yes)
		(dnp no)
		(fields_autoplaced yes)
		(property "Reference" "U4"
			(at 102.235 96.52 0)
			(effects
				(font
					(size 1.27 1.27)
				)
			)
		)
		(property "Value" "W25Q32JW_SOIC-8"
			(at 102.235 99.06 0)
			(effects
				(font
					(size 1.27 1.27)
					(thickness 0.15)
				)
				(hide yes)
			)
		)
		(property "Footprint" "antmicro-footprints:SOIC-8_5.3x5.3x2mm_P1.27mm"
			(at 125.73 113.03 0)
			(effects
				(font
					(size 1.27 1.27)
					(thickness 0.15)
				)
				(justify left bottom)
				(hide yes)
			)
		)
		(property "Datasheet" "https://www.mouser.com/datasheet/2/949/w25q32jw_spi_revf_09042018-1489621.pdf"
			(at 125.73 115.57 0)
			(effects
				(font
					(size 1.27 1.27)
					(thickness 0.15)
				)
				(justify left bottom)
				(hide yes)
			)
		)
		(property "Description" "FLASH - NOR Memory IC 32Mbit SPI - Quad I/O 133 MHz 8-SOIC"
			(at 92.71 104.14 0)
			(effects
				(font
					(size 1.27 1.27)
				)
				(hide yes)
			)
		)
		(property "MPN" "W25Q32JWSSIQ"
			(at 102.235 99.06 0)
			(effects
				(font
					(size 1.27 1.27)
					(thickness 0.15)
				)
			)
		)
		(property "Manufacturer" "Winbond"
			(at 125.73 120.65 0)
			(effects
				(font
					(size 1.27 1.27)
					(thickness 0.15)
				)
				(justify left bottom)
				(hide yes)
			)
		)
		(property "Author" "Antmicro"
			(at 125.73 123.19 0)
			(effects
				(font
					(size 1.27 1.27)
					(thickness 0.15)
				)
				(justify left bottom)
				(hide yes)
			)
		)
		(property "License" "Apache-2.0"
			(at 125.73 125.73 0)
			(effects
				(font
					(size 1.27 1.27)
					(thickness 0.15)
				)
				(justify left bottom)
				(hide yes)
			)
		)
		(pin "1"
		)
		(pin "2"
		)
		(pin "3"
		)
		(pin "4"
		)
		(pin "5"
		)
		(pin "6"
		)
		(pin "7"
		)
		(pin "8"
		)
		(instances
			(project "artix-dc-scm"
				(path ""
					(reference "U4")
					(unit 1)
				)
			)
		)
	)
	(symbol
		(lib_id "antmicroResistors0402:R_4k7_0402")
		(at 81.28 172.72 270)
		(unit 1)
		(exclude_from_sim no)
		(in_bom yes)
		(on_board yes)
		(dnp no)
		(property "Reference" "R22"
			(at 82.55 173.99 90)
			(effects
				(font
					(size 1.27 1.27)
				)
				(justify left)
			)
		)
		(property "Value" "R_4k7_0402"
			(at 68.58 193.04 0)
			(effects
				(font
					(size 1.27 1.27)
					(thickness 0.15)
				)
				(justify left bottom)
				(hide yes)
			)
		)
		(property "Footprint" "antmicro-footprints:R_0402_1005Metric"
			(at 66.04 193.04 0)
			(effects
				(font
					(size 1.27 1.27)
					(thickness 0.15)
				)
				(justify left bottom)
				(hide yes)
			)
		)
		(property "Datasheet" "https://www.bourns.com/docs/product-datasheets/cr.pdf"
			(at 63.5 193.04 0)
			(effects
				(font
					(size 1.27 1.27)
					(thickness 0.15)
				)
				(justify left bottom)
				(hide yes)
			)
		)
		(property "Description" "SMD Chip Resistor, 4.7 kohm, ± 1%, 62.5 mW, 0402 [1005 Metric], Thick Film, General Purpose"
			(at 81.28 172.72 0)
			(effects
				(font
					(size 1.27 1.27)
				)
				(hide yes)
			)
		)
		(property "Manufacturer" "Bourns"
			(at 58.42 193.04 0)
			(effects
				(font
					(size 1.27 1.27)
					(thickness 0.15)
				)
				(justify left bottom)
				(hide yes)
			)
		)
		(property "MPN" "CR0402-FX-4701GLF"
			(at 60.96 193.04 0)
			(effects
				(font
					(size 1.27 1.27)
					(thickness 0.15)
				)
				(justify left bottom)
				(hide yes)
			)
		)
		(property "Val" "4k7"
			(at 82.55 176.53 90)
			(effects
				(font
					(size 1.27 1.27)
					(thickness 0.15)
				)
				(justify left)
			)
		)
		(property "License" "Apache-2.0"
			(at 55.88 193.04 0)
			(effects
				(font
					(size 1.27 1.27)
					(thickness 0.15)
				)
				(justify left bottom)
				(hide yes)
			)
		)
		(property "Author" "Antmicro"
			(at 53.34 193.04 0)
			(effects
				(font
					(size 1.27 1.27)
					(thickness 0.15)
				)
				(justify left bottom)
				(hide yes)
			)
		)
		(property "Tolerance" "1%"
			(at 71.12 193.04 0)
			(effects
				(font
					(size 1.27 1.27)
				)
				(justify left bottom)
				(hide yes)
			)
		)
		(pin "1"
		)
		(pin "2"
		)
		(instances
			(project "artix-dc-scm"
				(path ""
					(reference "R22")
					(unit 1)
				)
			)
		)
	)
	(symbol
		(lib_id "antmicroResistors0402:R_1k_0402")
		(at 73.66 172.72 270)
		(unit 1)
		(exclude_from_sim no)
		(in_bom yes)
		(on_board yes)
		(dnp no)
		(property "Reference" "R26"
			(at 74.93 173.99 90)
			(effects
				(font
					(size 1.27 1.27)
				)
				(justify left)
			)
		)
		(property "Value" "R_1k_0402"
			(at 60.96 193.04 0)
			(effects
				(font
					(size 1.27 1.27)
					(thickness 0.15)
				)
				(justify left bottom)
				(hide yes)
			)
		)
		(property "Footprint" "antmicro-footprints:R_0402_1005Metric"
			(at 58.42 193.04 0)
			(effects
				(font
					(size 1.27 1.27)
					(thickness 0.15)
				)
				(justify left bottom)
				(hide yes)
			)
		)
		(property "Datasheet" "https://www.bourns.com/docs/product-datasheets/cr.pdf"
			(at 55.88 193.04 0)
			(effects
				(font
					(size 1.27 1.27)
					(thickness 0.15)
				)
				(justify left bottom)
				(hide yes)
			)
		)
		(property "Description" "SMD Chip Resistor, 1 kohm, ± 1%, 63 mW, 0402 [1005 Metric], Thick Film, General Purpose"
			(at 73.66 172.72 0)
			(effects
				(font
					(size 1.27 1.27)
				)
				(hide yes)
			)
		)
		(property "Manufacturer" "Bourns"
			(at 50.8 193.04 0)
			(effects
				(font
					(size 1.27 1.27)
					(thickness 0.15)
				)
				(justify left bottom)
				(hide yes)
			)
		)
		(property "MPN" "CR0402-FX-1001GLF"
			(at 53.34 193.04 0)
			(effects
				(font
					(size 1.27 1.27)
					(thickness 0.15)
				)
				(justify left bottom)
				(hide yes)
			)
		)
		(property "Val" "1k"
			(at 74.93 176.53 90)
			(effects
				(font
					(size 1.27 1.27)
					(thickness 0.15)
				)
				(justify left)
			)
		)
		(property "License" "Apache-2.0"
			(at 48.26 193.04 0)
			(effects
				(font
					(size 1.27 1.27)
					(thickness 0.15)
				)
				(justify left bottom)
				(hide yes)
			)
		)
		(property "Author" "Antmicro"
			(at 45.72 193.04 0)
			(effects
				(font
					(size 1.27 1.27)
					(thickness 0.15)
				)
				(justify left bottom)
				(hide yes)
			)
		)
		(property "Tolerance" "1%"
			(at 63.5 193.04 0)
			(effects
				(font
					(size 1.27 1.27)
				)
				(justify left bottom)
				(hide yes)
			)
		)
		(pin "1"
		)
		(pin "2"
		)
		(instances
			(project "artix-dc-scm"
				(path ""
					(reference "R26")
					(unit 1)
				)
			)
		)
	)
	(symbol
		(lib_id "antmicroResistors0402:R_10k_0402")
		(at 50.8 177.8 90)
		(unit 1)
		(exclude_from_sim no)
		(in_bom yes)
		(on_board yes)
		(dnp no)
		(property "Reference" "R30"
			(at 52.07 173.99 90)
			(effects
				(font
					(size 1.27 1.27)
				)
				(justify right)
			)
		)
		(property "Value" "R_10k_0402"
			(at 63.5 157.48 0)
			(effects
				(font
					(size 1.27 1.27)
					(thickness 0.15)
				)
				(justify left bottom)
				(hide yes)
			)
		)
		(property "Footprint" "antmicro-footprints:R_0402_1005Metric"
			(at 66.04 157.48 0)
			(effects
				(font
					(size 1.27 1.27)
					(thickness 0.15)
				)
				(justify left bottom)
				(hide yes)
			)
		)
		(property "Datasheet" "https://www.bourns.com/docs/product-datasheets/cr.pdf"
			(at 68.58 157.48 0)
			(effects
				(font
					(size 1.27 1.27)
					(thickness 0.15)
				)
				(justify left bottom)
				(hide yes)
			)
		)
		(property "Description" "SMD Chip Resistor, 10 kohm, ± 1%, 62.5 mW, 0402 [1005 Metric], Thick Film, General Purpose"
			(at 50.8 177.8 0)
			(effects
				(font
					(size 1.27 1.27)
				)
				(hide yes)
			)
		)
		(property "Manufacturer" "Bourns"
			(at 73.66 157.48 0)
			(effects
				(font
					(size 1.27 1.27)
					(thickness 0.15)
				)
				(justify left bottom)
				(hide yes)
			)
		)
		(property "MPN" "CR0402-FX-1002GLF"
			(at 71.12 157.48 0)
			(effects
				(font
					(size 1.27 1.27)
					(thickness 0.15)
				)
				(justify left bottom)
				(hide yes)
			)
		)
		(property "Val" "10k"
			(at 52.07 176.53 90)
			(effects
				(font
					(size 1.27 1.27)
					(thickness 0.15)
				)
				(justify right)
			)
		)
		(property "License" "Apache-2.0"
			(at 76.2 157.48 0)
			(effects
				(font
					(size 1.27 1.27)
					(thickness 0.15)
				)
				(justify left bottom)
				(hide yes)
			)
		)
		(property "Author" "Antmicro"
			(at 78.74 157.48 0)
			(effects
				(font
					(size 1.27 1.27)
					(thickness 0.15)
				)
				(justify left bottom)
				(hide yes)
			)
		)
		(property "Tolerance" "1%"
			(at 60.96 157.48 0)
			(effects
				(font
					(size 1.27 1.27)
				)
				(justify left bottom)
				(hide yes)
			)
		)
		(pin "1"
		)
		(pin "2"
		)
		(instances
			(project "artix-dc-scm"
				(path ""
					(reference "R30")
					(unit 1)
				)
			)
		)
	)
	(symbol
		(lib_id "antmicroResistors0402:R_10k_0402")
		(at 66.04 177.8 90)
		(unit 1)
		(exclude_from_sim no)
		(in_bom yes)
		(on_board yes)
		(dnp no)
		(property "Reference" "R38"
			(at 67.31 173.99 90)
			(effects
				(font
					(size 1.27 1.27)
				)
				(justify right)
			)
		)
		(property "Value" "R_10k_0402"
			(at 78.74 157.48 0)
			(effects
				(font
					(size 1.27 1.27)
					(thickness 0.15)
				)
				(justify left bottom)
				(hide yes)
			)
		)
		(property "Footprint" "antmicro-footprints:R_0402_1005Metric"
			(at 81.28 157.48 0)
			(effects
				(font
					(size 1.27 1.27)
					(thickness 0.15)
				)
				(justify left bottom)
				(hide yes)
			)
		)
		(property "Datasheet" "https://www.bourns.com/docs/product-datasheets/cr.pdf"
			(at 83.82 157.48 0)
			(effects
				(font
					(size 1.27 1.27)
					(thickness 0.15)
				)
				(justify left bottom)
				(hide yes)
			)
		)
		(property "Description" "SMD Chip Resistor, 10 kohm, ± 1%, 62.5 mW, 0402 [1005 Metric], Thick Film, General Purpose"
			(at 66.04 177.8 0)
			(effects
				(font
					(size 1.27 1.27)
				)
				(hide yes)
			)
		)
		(property "Manufacturer" "Bourns"
			(at 88.9 157.48 0)
			(effects
				(font
					(size 1.27 1.27)
					(thickness 0.15)
				)
				(justify left bottom)
				(hide yes)
			)
		)
		(property "MPN" "CR0402-FX-1002GLF"
			(at 86.36 157.48 0)
			(effects
				(font
					(size 1.27 1.27)
					(thickness 0.15)
				)
				(justify left bottom)
				(hide yes)
			)
		)
		(property "Val" "10k"
			(at 67.31 176.53 90)
			(effects
				(font
					(size 1.27 1.27)
					(thickness 0.15)
				)
				(justify right)
			)
		)
		(property "License" "Apache-2.0"
			(at 91.44 157.48 0)
			(effects
				(font
					(size 1.27 1.27)
					(thickness 0.15)
				)
				(justify left bottom)
				(hide yes)
			)
		)
		(property "Author" "Antmicro"
			(at 93.98 157.48 0)
			(effects
				(font
					(size 1.27 1.27)
					(thickness 0.15)
				)
				(justify left bottom)
				(hide yes)
			)
		)
		(property "Tolerance" "1%"
			(at 76.2 157.48 0)
			(effects
				(font
					(size 1.27 1.27)
				)
				(justify left bottom)
				(hide yes)
			)
		)
		(pin "1"
		)
		(pin "2"
		)
		(instances
			(project "artix-dc-scm"
				(path ""
					(reference "R38")
					(unit 1)
				)
			)
		)
	)
	(symbol
		(lib_id "antmicroResistors0402:R_10k_0402")
		(at 43.18 177.8 270)
		(mirror x)
		(unit 1)
		(exclude_from_sim no)
		(in_bom yes)
		(on_board yes)
		(dnp no)
		(property "Reference" "R42"
			(at 44.45 173.99 90)
			(effects
				(font
					(size 1.27 1.27)
				)
				(justify left)
			)
		)
		(property "Value" "R_10k_0402"
			(at 30.48 157.48 0)
			(effects
				(font
					(size 1.27 1.27)
					(thickness 0.15)
				)
				(justify left bottom)
				(hide yes)
			)
		)
		(property "Footprint" "antmicro-footprints:R_0402_1005Metric"
			(at 27.94 157.48 0)
			(effects
				(font
					(size 1.27 1.27)
					(thickness 0.15)
				)
				(justify left bottom)
				(hide yes)
			)
		)
		(property "Datasheet" "https://www.bourns.com/docs/product-datasheets/cr.pdf"
			(at 25.4 157.48 0)
			(effects
				(font
					(size 1.27 1.27)
					(thickness 0.15)
				)
				(justify left bottom)
				(hide yes)
			)
		)
		(property "Description" "SMD Chip Resistor, 10 kohm, ± 1%, 62.5 mW, 0402 [1005 Metric], Thick Film, General Purpose"
			(at 43.18 177.8 0)
			(effects
				(font
					(size 1.27 1.27)
				)
				(hide yes)
			)
		)
		(property "Manufacturer" "Bourns"
			(at 20.32 157.48 0)
			(effects
				(font
					(size 1.27 1.27)
					(thickness 0.15)
				)
				(justify left bottom)
				(hide yes)
			)
		)
		(property "MPN" "CR0402-FX-1002GLF"
			(at 22.86 157.48 0)
			(effects
				(font
					(size 1.27 1.27)
					(thickness 0.15)
				)
				(justify left bottom)
				(hide yes)
			)
		)
		(property "Val" "10k"
			(at 44.45 176.53 90)
			(effects
				(font
					(size 1.27 1.27)
					(thickness 0.15)
				)
				(justify left)
			)
		)
		(property "License" "Apache-2.0"
			(at 17.78 157.48 0)
			(effects
				(font
					(size 1.27 1.27)
					(thickness 0.15)
				)
				(justify left bottom)
				(hide yes)
			)
		)
		(property "Author" "Antmicro"
			(at 15.24 157.48 0)
			(effects
				(font
					(size 1.27 1.27)
					(thickness 0.15)
				)
				(justify left bottom)
				(hide yes)
			)
		)
		(property "Tolerance" "1%"
			(at 33.02 157.48 0)
			(effects
				(font
					(size 1.27 1.27)
				)
				(justify left bottom)
				(hide yes)
			)
		)
		(pin "1"
		)
		(pin "2"
		)
		(instances
			(project "artix-dc-scm"
				(path ""
					(reference "R42")
					(unit 1)
				)
			)
		)
	)
	(symbol
		(lib_id "antmicroCapacitors0402:C_470n_0402")
		(at 113.03 189.23 90)
		(unit 1)
		(exclude_from_sim no)
		(in_bom yes)
		(on_board yes)
		(dnp no)
		(property "Reference" "C36"
			(at 113.665 184.785 90)
			(effects
				(font
					(size 1.27 1.27)
				)
				(justify right)
			)
		)
		(property "Value" "C_470n_0402"
			(at 123.19 168.91 0)
			(effects
				(font
					(size 1.27 1.27)
					(thickness 0.15)
				)
				(justify left bottom)
				(hide yes)
			)
		)
		(property "Footprint" "antmicro-footprints:C_0402_1005Metric"
			(at 125.73 168.91 0)
			(effects
				(font
					(size 1.27 1.27)
					(thickness 0.15)
				)
				(justify left bottom)
				(hide yes)
			)
		)
		(property "Datasheet" "https://product.tdk.com/en/search/capacitor/ceramic/mlcc/info?part_no=C1005X5R1E474M050BB"
			(at 128.27 168.91 0)
			(effects
				(font
					(size 1.27 1.27)
					(thickness 0.15)
				)
				(justify left bottom)
				(hide yes)
			)
		)
		(property "Description" "SMD Multilayer Ceramic Capacitor, 0.47 µF, 25 V, 0402 [1005 Metric], ± 20%, X5R, C"
			(at 113.03 189.23 0)
			(effects
				(font
					(size 1.27 1.27)
				)
				(hide yes)
			)
		)
		(property "Manufacturer" "TDK"
			(at 133.35 168.91 0)
			(effects
				(font
					(size 1.27 1.27)
					(thickness 0.15)
				)
				(justify left bottom)
				(hide yes)
			)
		)
		(property "MPN" "C1005X5R1E474M050BB"
			(at 130.81 168.91 0)
			(effects
				(font
					(size 1.27 1.27)
					(thickness 0.15)
				)
				(justify left bottom)
				(hide yes)
			)
		)
		(property "Val" "470n"
			(at 113.665 188.595 90)
			(effects
				(font
					(size 1.27 1.27)
					(thickness 0.15)
				)
				(justify right)
			)
		)
		(property "License" "Apache-2.0"
			(at 135.89 168.91 0)
			(effects
				(font
					(size 1.27 1.27)
					(thickness 0.15)
				)
				(justify left bottom)
				(hide yes)
			)
		)
		(property "Author" "Antmicro"
			(at 138.43 168.91 0)
			(effects
				(font
					(size 1.27 1.27)
					(thickness 0.15)
				)
				(justify left bottom)
				(hide yes)
			)
		)
		(property "Voltage" ""
			(at 140.97 168.91 0)
			(effects
				(font
					(size 1.27 1.27)
				)
				(justify left bottom)
				(hide yes)
			)
		)
		(property "Dielectric" ""
			(at 143.51 168.91 0)
			(effects
				(font
					(size 1.27 1.27)
				)
				(justify left bottom)
				(hide yes)
			)
		)
		(pin "1"
		)
		(pin "2"
		)
		(instances
			(project "artix-dc-scm"
				(path ""
					(reference "C36")
					(unit 1)
				)
			)
		)
	)
	(symbol
		(lib_id "antmicroResistors0402:R_10k_0402")
		(at 58.42 177.8 90)
		(unit 1)
		(exclude_from_sim no)
		(in_bom yes)
		(on_board yes)
		(dnp no)
		(property "Reference" "R34"
			(at 59.69 173.99 90)
			(effects
				(font
					(size 1.27 1.27)
				)
				(justify right)
			)
		)
		(property "Value" "R_10k_0402"
			(at 71.12 157.48 0)
			(effects
				(font
					(size 1.27 1.27)
					(thickness 0.15)
				)
				(justify left bottom)
				(hide yes)
			)
		)
		(property "Footprint" "antmicro-footprints:R_0402_1005Metric"
			(at 73.66 157.48 0)
			(effects
				(font
					(size 1.27 1.27)
					(thickness 0.15)
				)
				(justify left bottom)
				(hide yes)
			)
		)
		(property "Datasheet" "https://www.bourns.com/docs/product-datasheets/cr.pdf"
			(at 76.2 157.48 0)
			(effects
				(font
					(size 1.27 1.27)
					(thickness 0.15)
				)
				(justify left bottom)
				(hide yes)
			)
		)
		(property "Description" "SMD Chip Resistor, 10 kohm, ± 1%, 62.5 mW, 0402 [1005 Metric], Thick Film, General Purpose"
			(at 58.42 177.8 0)
			(effects
				(font
					(size 1.27 1.27)
				)
				(hide yes)
			)
		)
		(property "Manufacturer" "Bourns"
			(at 81.28 157.48 0)
			(effects
				(font
					(size 1.27 1.27)
					(thickness 0.15)
				)
				(justify left bottom)
				(hide yes)
			)
		)
		(property "MPN" "CR0402-FX-1002GLF"
			(at 78.74 157.48 0)
			(effects
				(font
					(size 1.27 1.27)
					(thickness 0.15)
				)
				(justify left bottom)
				(hide yes)
			)
		)
		(property "Val" "10k"
			(at 59.69 176.53 90)
			(effects
				(font
					(size 1.27 1.27)
					(thickness 0.15)
				)
				(justify right)
			)
		)
		(property "License" "Apache-2.0"
			(at 83.82 157.48 0)
			(effects
				(font
					(size 1.27 1.27)
					(thickness 0.15)
				)
				(justify left bottom)
				(hide yes)
			)
		)
		(property "Author" "Antmicro"
			(at 86.36 157.48 0)
			(effects
				(font
					(size 1.27 1.27)
					(thickness 0.15)
				)
				(justify left bottom)
				(hide yes)
			)
		)
		(property "Tolerance" "1%"
			(at 68.58 157.48 0)
			(effects
				(font
					(size 1.27 1.27)
				)
				(justify left bottom)
				(hide yes)
			)
		)
		(pin "1"
		)
		(pin "2"
		)
		(instances
			(project "artix-dc-scm"
				(path ""
					(reference "R34")
					(unit 1)
				)
			)
		)
	)
	(symbol
		(lib_id "antmicroMemory:W25Q32JW_SOIC-8")
		(at 92.71 180.34 0)
		(unit 1)
		(exclude_from_sim no)
		(in_bom yes)
		(on_board yes)
		(dnp no)
		(fields_autoplaced yes)
		(property "Reference" "U3"
			(at 102.235 172.72 0)
			(effects
				(font
					(size 1.27 1.27)
				)
			)
		)
		(property "Value" "W25Q32JW_SOIC-8"
			(at 102.235 174.625 0)
			(effects
				(font
					(size 1.27 1.27)
					(thickness 0.15)
				)
				(hide yes)
			)
		)
		(property "Footprint" "antmicro-footprints:SOIC-8_5.3x5.3x2mm_P1.27mm"
			(at 125.73 189.23 0)
			(effects
				(font
					(size 1.27 1.27)
					(thickness 0.15)
				)
				(justify left bottom)
				(hide yes)
			)
		)
		(property "Datasheet" "https://www.mouser.com/datasheet/2/949/w25q32jw_spi_revf_09042018-1489621.pdf"
			(at 125.73 191.77 0)
			(effects
				(font
					(size 1.27 1.27)
					(thickness 0.15)
				)
				(justify left bottom)
				(hide yes)
			)
		)
		(property "Description" "FLASH - NOR Memory IC 32Mbit SPI - Quad I/O 133 MHz 8-SOIC"
			(at 92.71 180.34 0)
			(effects
				(font
					(size 1.27 1.27)
				)
				(hide yes)
			)
		)
		(property "MPN" "W25Q32JWSSIQ"
			(at 102.235 175.26 0)
			(effects
				(font
					(size 1.27 1.27)
					(thickness 0.15)
				)
			)
		)
		(property "Manufacturer" "Winbond"
			(at 125.73 196.85 0)
			(effects
				(font
					(size 1.27 1.27)
					(thickness 0.15)
				)
				(justify left bottom)
				(hide yes)
			)
		)
		(property "Author" "Antmicro"
			(at 125.73 199.39 0)
			(effects
				(font
					(size 1.27 1.27)
					(thickness 0.15)
				)
				(justify left bottom)
				(hide yes)
			)
		)
		(property "License" "Apache-2.0"
			(at 125.73 201.93 0)
			(effects
				(font
					(size 1.27 1.27)
					(thickness 0.15)
				)
				(justify left bottom)
				(hide yes)
			)
		)
		(pin "1"
		)
		(pin "2"
		)
		(pin "3"
		)
		(pin "4"
		)
		(pin "5"
		)
		(pin "6"
		)
		(pin "7"
		)
		(pin "8"
		)
		(instances
			(project "artix-dc-scm"
				(path ""
					(reference "U3")
					(unit 1)
				)
			)
		)
	)
	(symbol
		(lib_id "antmicroResistors0402:R_4k7_0402")
		(at 81.28 223.52 270)
		(unit 1)
		(exclude_from_sim no)
		(in_bom yes)
		(on_board yes)
		(dnp no)
		(property "Reference" "R21"
			(at 82.55 224.79 90)
			(effects
				(font
					(size 1.27 1.27)
				)
				(justify left)
			)
		)
		(property "Value" "R_4k7_0402"
			(at 68.58 243.84 0)
			(effects
				(font
					(size 1.27 1.27)
					(thickness 0.15)
				)
				(justify left bottom)
				(hide yes)
			)
		)
		(property "Footprint" "antmicro-footprints:R_0402_1005Metric"
			(at 66.04 243.84 0)
			(effects
				(font
					(size 1.27 1.27)
					(thickness 0.15)
				)
				(justify left bottom)
				(hide yes)
			)
		)
		(property "Datasheet" "https://www.bourns.com/docs/product-datasheets/cr.pdf"
			(at 63.5 243.84 0)
			(effects
				(font
					(size 1.27 1.27)
					(thickness 0.15)
				)
				(justify left bottom)
				(hide yes)
			)
		)
		(property "Description" "SMD Chip Resistor, 4.7 kohm, ± 1%, 62.5 mW, 0402 [1005 Metric], Thick Film, General Purpose"
			(at 81.28 223.52 0)
			(effects
				(font
					(size 1.27 1.27)
				)
				(hide yes)
			)
		)
		(property "Manufacturer" "Bourns"
			(at 58.42 243.84 0)
			(effects
				(font
					(size 1.27 1.27)
					(thickness 0.15)
				)
				(justify left bottom)
				(hide yes)
			)
		)
		(property "MPN" "CR0402-FX-4701GLF"
			(at 60.96 243.84 0)
			(effects
				(font
					(size 1.27 1.27)
					(thickness 0.15)
				)
				(justify left bottom)
				(hide yes)
			)
		)
		(property "Val" "4k7"
			(at 82.55 227.33 90)
			(effects
				(font
					(size 1.27 1.27)
					(thickness 0.15)
				)
				(justify left)
			)
		)
		(property "License" "Apache-2.0"
			(at 55.88 243.84 0)
			(effects
				(font
					(size 1.27 1.27)
					(thickness 0.15)
				)
				(justify left bottom)
				(hide yes)
			)
		)
		(property "Author" "Antmicro"
			(at 53.34 243.84 0)
			(effects
				(font
					(size 1.27 1.27)
					(thickness 0.15)
				)
				(justify left bottom)
				(hide yes)
			)
		)
		(property "Tolerance" "1%"
			(at 71.12 243.84 0)
			(effects
				(font
					(size 1.27 1.27)
				)
				(justify left bottom)
				(hide yes)
			)
		)
		(pin "1"
		)
		(pin "2"
		)
		(instances
			(project "artix-dc-scm"
				(path ""
					(reference "R21")
					(unit 1)
				)
			)
		)
	)
	(symbol
		(lib_id "antmicroResistors0402:R_1k_0402")
		(at 73.66 223.52 270)
		(unit 1)
		(exclude_from_sim no)
		(in_bom yes)
		(on_board yes)
		(dnp no)
		(property "Reference" "R25"
			(at 74.93 224.79 90)
			(effects
				(font
					(size 1.27 1.27)
				)
				(justify left)
			)
		)
		(property "Value" "R_1k_0402"
			(at 60.96 243.84 0)
			(effects
				(font
					(size 1.27 1.27)
					(thickness 0.15)
				)
				(justify left bottom)
				(hide yes)
			)
		)
		(property "Footprint" "antmicro-footprints:R_0402_1005Metric"
			(at 58.42 243.84 0)
			(effects
				(font
					(size 1.27 1.27)
					(thickness 0.15)
				)
				(justify left bottom)
				(hide yes)
			)
		)
		(property "Datasheet" "https://www.bourns.com/docs/product-datasheets/cr.pdf"
			(at 55.88 243.84 0)
			(effects
				(font
					(size 1.27 1.27)
					(thickness 0.15)
				)
				(justify left bottom)
				(hide yes)
			)
		)
		(property "Description" "SMD Chip Resistor, 1 kohm, ± 1%, 63 mW, 0402 [1005 Metric], Thick Film, General Purpose"
			(at 73.66 223.52 0)
			(effects
				(font
					(size 1.27 1.27)
				)
				(hide yes)
			)
		)
		(property "Manufacturer" "Bourns"
			(at 50.8 243.84 0)
			(effects
				(font
					(size 1.27 1.27)
					(thickness 0.15)
				)
				(justify left bottom)
				(hide yes)
			)
		)
		(property "MPN" "CR0402-FX-1001GLF"
			(at 53.34 243.84 0)
			(effects
				(font
					(size 1.27 1.27)
					(thickness 0.15)
				)
				(justify left bottom)
				(hide yes)
			)
		)
		(property "Val" "1k"
			(at 74.93 227.33 90)
			(effects
				(font
					(size 1.27 1.27)
					(thickness 0.15)
				)
				(justify left)
			)
		)
		(property "License" "Apache-2.0"
			(at 48.26 243.84 0)
			(effects
				(font
					(size 1.27 1.27)
					(thickness 0.15)
				)
				(justify left bottom)
				(hide yes)
			)
		)
		(property "Author" "Antmicro"
			(at 45.72 243.84 0)
			(effects
				(font
					(size 1.27 1.27)
					(thickness 0.15)
				)
				(justify left bottom)
				(hide yes)
			)
		)
		(property "Tolerance" "1%"
			(at 63.5 243.84 0)
			(effects
				(font
					(size 1.27 1.27)
				)
				(justify left bottom)
				(hide yes)
			)
		)
		(pin "1"
		)
		(pin "2"
		)
		(instances
			(project "artix-dc-scm"
				(path ""
					(reference "R25")
					(unit 1)
				)
			)
		)
	)
	(symbol
		(lib_id "antmicroResistors0402:R_10k_0402")
		(at 50.8 228.6 90)
		(unit 1)
		(exclude_from_sim no)
		(in_bom yes)
		(on_board yes)
		(dnp no)
		(property "Reference" "R29"
			(at 52.07 224.79 90)
			(effects
				(font
					(size 1.27 1.27)
				)
				(justify right)
			)
		)
		(property "Value" "R_10k_0402"
			(at 63.5 208.28 0)
			(effects
				(font
					(size 1.27 1.27)
					(thickness 0.15)
				)
				(justify left bottom)
				(hide yes)
			)
		)
		(property "Footprint" "antmicro-footprints:R_0402_1005Metric"
			(at 66.04 208.28 0)
			(effects
				(font
					(size 1.27 1.27)
					(thickness 0.15)
				)
				(justify left bottom)
				(hide yes)
			)
		)
		(property "Datasheet" "https://www.bourns.com/docs/product-datasheets/cr.pdf"
			(at 68.58 208.28 0)
			(effects
				(font
					(size 1.27 1.27)
					(thickness 0.15)
				)
				(justify left bottom)
				(hide yes)
			)
		)
		(property "Description" "SMD Chip Resistor, 10 kohm, ± 1%, 62.5 mW, 0402 [1005 Metric], Thick Film, General Purpose"
			(at 50.8 228.6 0)
			(effects
				(font
					(size 1.27 1.27)
				)
				(hide yes)
			)
		)
		(property "Manufacturer" "Bourns"
			(at 73.66 208.28 0)
			(effects
				(font
					(size 1.27 1.27)
					(thickness 0.15)
				)
				(justify left bottom)
				(hide yes)
			)
		)
		(property "MPN" "CR0402-FX-1002GLF"
			(at 71.12 208.28 0)
			(effects
				(font
					(size 1.27 1.27)
					(thickness 0.15)
				)
				(justify left bottom)
				(hide yes)
			)
		)
		(property "Val" "10k"
			(at 52.07 227.33 90)
			(effects
				(font
					(size 1.27 1.27)
					(thickness 0.15)
				)
				(justify right)
			)
		)
		(property "License" "Apache-2.0"
			(at 76.2 208.28 0)
			(effects
				(font
					(size 1.27 1.27)
					(thickness 0.15)
				)
				(justify left bottom)
				(hide yes)
			)
		)
		(property "Author" "Antmicro"
			(at 78.74 208.28 0)
			(effects
				(font
					(size 1.27 1.27)
					(thickness 0.15)
				)
				(justify left bottom)
				(hide yes)
			)
		)
		(property "Tolerance" "1%"
			(at 60.96 208.28 0)
			(effects
				(font
					(size 1.27 1.27)
				)
				(justify left bottom)
				(hide yes)
			)
		)
		(pin "1"
		)
		(pin "2"
		)
		(instances
			(project "artix-dc-scm"
				(path ""
					(reference "R29")
					(unit 1)
				)
			)
		)
	)
	(symbol
		(lib_id "antmicroResistors0402:R_10k_0402")
		(at 66.04 228.6 90)
		(unit 1)
		(exclude_from_sim no)
		(in_bom yes)
		(on_board yes)
		(dnp no)
		(property "Reference" "R37"
			(at 67.31 224.79 90)
			(effects
				(font
					(size 1.27 1.27)
				)
				(justify right)
			)
		)
		(property "Value" "R_10k_0402"
			(at 78.74 208.28 0)
			(effects
				(font
					(size 1.27 1.27)
					(thickness 0.15)
				)
				(justify left bottom)
				(hide yes)
			)
		)
		(property "Footprint" "antmicro-footprints:R_0402_1005Metric"
			(at 81.28 208.28 0)
			(effects
				(font
					(size 1.27 1.27)
					(thickness 0.15)
				)
				(justify left bottom)
				(hide yes)
			)
		)
		(property "Datasheet" "https://www.bourns.com/docs/product-datasheets/cr.pdf"
			(at 83.82 208.28 0)
			(effects
				(font
					(size 1.27 1.27)
					(thickness 0.15)
				)
				(justify left bottom)
				(hide yes)
			)
		)
		(property "Description" "SMD Chip Resistor, 10 kohm, ± 1%, 62.5 mW, 0402 [1005 Metric], Thick Film, General Purpose"
			(at 66.04 228.6 0)
			(effects
				(font
					(size 1.27 1.27)
				)
				(hide yes)
			)
		)
		(property "Manufacturer" "Bourns"
			(at 88.9 208.28 0)
			(effects
				(font
					(size 1.27 1.27)
					(thickness 0.15)
				)
				(justify left bottom)
				(hide yes)
			)
		)
		(property "MPN" "CR0402-FX-1002GLF"
			(at 86.36 208.28 0)
			(effects
				(font
					(size 1.27 1.27)
					(thickness 0.15)
				)
				(justify left bottom)
				(hide yes)
			)
		)
		(property "Val" "10k"
			(at 67.31 227.33 90)
			(effects
				(font
					(size 1.27 1.27)
					(thickness 0.15)
				)
				(justify right)
			)
		)
		(property "License" "Apache-2.0"
			(at 91.44 208.28 0)
			(effects
				(font
					(size 1.27 1.27)
					(thickness 0.15)
				)
				(justify left bottom)
				(hide yes)
			)
		)
		(property "Author" "Antmicro"
			(at 93.98 208.28 0)
			(effects
				(font
					(size 1.27 1.27)
					(thickness 0.15)
				)
				(justify left bottom)
				(hide yes)
			)
		)
		(property "Tolerance" "1%"
			(at 76.2 208.28 0)
			(effects
				(font
					(size 1.27 1.27)
				)
				(justify left bottom)
				(hide yes)
			)
		)
		(pin "1"
		)
		(pin "2"
		)
		(instances
			(project "artix-dc-scm"
				(path ""
					(reference "R37")
					(unit 1)
				)
			)
		)
	)
	(symbol
		(lib_id "antmicroResistors0402:R_10k_0402")
		(at 43.18 228.6 270)
		(mirror x)
		(unit 1)
		(exclude_from_sim no)
		(in_bom yes)
		(on_board yes)
		(dnp no)
		(property "Reference" "R41"
			(at 44.45 224.79 90)
			(effects
				(font
					(size 1.27 1.27)
				)
				(justify left)
			)
		)
		(property "Value" "R_10k_0402"
			(at 30.48 208.28 0)
			(effects
				(font
					(size 1.27 1.27)
					(thickness 0.15)
				)
				(justify left bottom)
				(hide yes)
			)
		)
		(property "Footprint" "antmicro-footprints:R_0402_1005Metric"
			(at 27.94 208.28 0)
			(effects
				(font
					(size 1.27 1.27)
					(thickness 0.15)
				)
				(justify left bottom)
				(hide yes)
			)
		)
		(property "Datasheet" "https://www.bourns.com/docs/product-datasheets/cr.pdf"
			(at 25.4 208.28 0)
			(effects
				(font
					(size 1.27 1.27)
					(thickness 0.15)
				)
				(justify left bottom)
				(hide yes)
			)
		)
		(property "Description" "SMD Chip Resistor, 10 kohm, ± 1%, 62.5 mW, 0402 [1005 Metric], Thick Film, General Purpose"
			(at 43.18 228.6 0)
			(effects
				(font
					(size 1.27 1.27)
				)
				(hide yes)
			)
		)
		(property "Manufacturer" "Bourns"
			(at 20.32 208.28 0)
			(effects
				(font
					(size 1.27 1.27)
					(thickness 0.15)
				)
				(justify left bottom)
				(hide yes)
			)
		)
		(property "MPN" "CR0402-FX-1002GLF"
			(at 22.86 208.28 0)
			(effects
				(font
					(size 1.27 1.27)
					(thickness 0.15)
				)
				(justify left bottom)
				(hide yes)
			)
		)
		(property "Val" "10k"
			(at 44.45 227.33 90)
			(effects
				(font
					(size 1.27 1.27)
					(thickness 0.15)
				)
				(justify left)
			)
		)
		(property "License" "Apache-2.0"
			(at 17.78 208.28 0)
			(effects
				(font
					(size 1.27 1.27)
					(thickness 0.15)
				)
				(justify left bottom)
				(hide yes)
			)
		)
		(property "Author" "Antmicro"
			(at 15.24 208.28 0)
			(effects
				(font
					(size 1.27 1.27)
					(thickness 0.15)
				)
				(justify left bottom)
				(hide yes)
			)
		)
		(property "Tolerance" "1%"
			(at 33.02 208.28 0)
			(effects
				(font
					(size 1.27 1.27)
				)
				(justify left bottom)
				(hide yes)
			)
		)
		(pin "1"
		)
		(pin "2"
		)
		(instances
			(project "artix-dc-scm"
				(path ""
					(reference "R41")
					(unit 1)
				)
			)
		)
	)
	(symbol
		(lib_id "antmicroCapacitors0402:C_470n_0402")
		(at 113.03 240.03 90)
		(unit 1)
		(exclude_from_sim no)
		(in_bom yes)
		(on_board yes)
		(dnp no)
		(property "Reference" "C35"
			(at 113.665 235.585 90)
			(effects
				(font
					(size 1.27 1.27)
				)
				(justify right)
			)
		)
		(property "Value" "C_470n_0402"
			(at 123.19 219.71 0)
			(effects
				(font
					(size 1.27 1.27)
					(thickness 0.15)
				)
				(justify left bottom)
				(hide yes)
			)
		)
		(property "Footprint" "antmicro-footprints:C_0402_1005Metric"
			(at 125.73 219.71 0)
			(effects
				(font
					(size 1.27 1.27)
					(thickness 0.15)
				)
				(justify left bottom)
				(hide yes)
			)
		)
		(property "Datasheet" "https://product.tdk.com/en/search/capacitor/ceramic/mlcc/info?part_no=C1005X5R1E474M050BB"
			(at 128.27 219.71 0)
			(effects
				(font
					(size 1.27 1.27)
					(thickness 0.15)
				)
				(justify left bottom)
				(hide yes)
			)
		)
		(property "Description" "SMD Multilayer Ceramic Capacitor, 0.47 µF, 25 V, 0402 [1005 Metric], ± 20%, X5R, C"
			(at 113.03 240.03 0)
			(effects
				(font
					(size 1.27 1.27)
				)
				(hide yes)
			)
		)
		(property "Manufacturer" "TDK"
			(at 133.35 219.71 0)
			(effects
				(font
					(size 1.27 1.27)
					(thickness 0.15)
				)
				(justify left bottom)
				(hide yes)
			)
		)
		(property "MPN" "C1005X5R1E474M050BB"
			(at 130.81 219.71 0)
			(effects
				(font
					(size 1.27 1.27)
					(thickness 0.15)
				)
				(justify left bottom)
				(hide yes)
			)
		)
		(property "Val" "470n"
			(at 113.665 239.395 90)
			(effects
				(font
					(size 1.27 1.27)
					(thickness 0.15)
				)
				(justify right)
			)
		)
		(property "License" "Apache-2.0"
			(at 135.89 219.71 0)
			(effects
				(font
					(size 1.27 1.27)
					(thickness 0.15)
				)
				(justify left bottom)
				(hide yes)
			)
		)
		(property "Author" "Antmicro"
			(at 138.43 219.71 0)
			(effects
				(font
					(size 1.27 1.27)
					(thickness 0.15)
				)
				(justify left bottom)
				(hide yes)
			)
		)
		(property "Voltage" ""
			(at 140.97 219.71 0)
			(effects
				(font
					(size 1.27 1.27)
				)
				(justify left bottom)
				(hide yes)
			)
		)
		(property "Dielectric" ""
			(at 143.51 219.71 0)
			(effects
				(font
					(size 1.27 1.27)
				)
				(justify left bottom)
				(hide yes)
			)
		)
		(pin "1"
		)
		(pin "2"
		)
		(instances
			(project "artix-dc-scm"
				(path ""
					(reference "C35")
					(unit 1)
				)
			)
		)
	)
	(symbol
		(lib_id "antmicroResistors0402:R_10k_0402")
		(at 58.42 228.6 90)
		(unit 1)
		(exclude_from_sim no)
		(in_bom yes)
		(on_board yes)
		(dnp no)
		(property "Reference" "R33"
			(at 59.69 224.79 90)
			(effects
				(font
					(size 1.27 1.27)
				)
				(justify right)
			)
		)
		(property "Value" "R_10k_0402"
			(at 71.12 208.28 0)
			(effects
				(font
					(size 1.27 1.27)
					(thickness 0.15)
				)
				(justify left bottom)
				(hide yes)
			)
		)
		(property "Footprint" "antmicro-footprints:R_0402_1005Metric"
			(at 73.66 208.28 0)
			(effects
				(font
					(size 1.27 1.27)
					(thickness 0.15)
				)
				(justify left bottom)
				(hide yes)
			)
		)
		(property "Datasheet" "https://www.bourns.com/docs/product-datasheets/cr.pdf"
			(at 76.2 208.28 0)
			(effects
				(font
					(size 1.27 1.27)
					(thickness 0.15)
				)
				(justify left bottom)
				(hide yes)
			)
		)
		(property "Description" "SMD Chip Resistor, 10 kohm, ± 1%, 62.5 mW, 0402 [1005 Metric], Thick Film, General Purpose"
			(at 58.42 228.6 0)
			(effects
				(font
					(size 1.27 1.27)
				)
				(hide yes)
			)
		)
		(property "Manufacturer" "Bourns"
			(at 81.28 208.28 0)
			(effects
				(font
					(size 1.27 1.27)
					(thickness 0.15)
				)
				(justify left bottom)
				(hide yes)
			)
		)
		(property "MPN" "CR0402-FX-1002GLF"
			(at 78.74 208.28 0)
			(effects
				(font
					(size 1.27 1.27)
					(thickness 0.15)
				)
				(justify left bottom)
				(hide yes)
			)
		)
		(property "Val" "10k"
			(at 59.69 227.33 90)
			(effects
				(font
					(size 1.27 1.27)
					(thickness 0.15)
				)
				(justify right)
			)
		)
		(property "License" "Apache-2.0"
			(at 83.82 208.28 0)
			(effects
				(font
					(size 1.27 1.27)
					(thickness 0.15)
				)
				(justify left bottom)
				(hide yes)
			)
		)
		(property "Author" "Antmicro"
			(at 86.36 208.28 0)
			(effects
				(font
					(size 1.27 1.27)
					(thickness 0.15)
				)
				(justify left bottom)
				(hide yes)
			)
		)
		(property "Tolerance" "1%"
			(at 68.58 208.28 0)
			(effects
				(font
					(size 1.27 1.27)
				)
				(justify left bottom)
				(hide yes)
			)
		)
		(pin "1"
		)
		(pin "2"
		)
		(instances
			(project "artix-dc-scm"
				(path ""
					(reference "R33")
					(unit 1)
				)
			)
		)
	)
	(symbol
		(lib_id "antmicroMemory:W25Q32JW_SOIC-8")
		(at 92.71 231.14 0)
		(unit 1)
		(exclude_from_sim no)
		(in_bom yes)
		(on_board yes)
		(dnp no)
		(fields_autoplaced yes)
		(property "Reference" "U2"
			(at 102.235 223.52 0)
			(effects
				(font
					(size 1.27 1.27)
				)
			)
		)
		(property "Value" "W25Q32JW_SOIC-8"
			(at 102.235 226.06 0)
			(effects
				(font
					(size 1.27 1.27)
					(thickness 0.15)
				)
				(hide yes)
			)
		)
		(property "Footprint" "antmicro-footprints:SOIC-8_5.3x5.3x2mm_P1.27mm"
			(at 125.73 240.03 0)
			(effects
				(font
					(size 1.27 1.27)
					(thickness 0.15)
				)
				(justify left bottom)
				(hide yes)
			)
		)
		(property "Datasheet" "https://www.mouser.com/datasheet/2/949/w25q32jw_spi_revf_09042018-1489621.pdf"
			(at 125.73 242.57 0)
			(effects
				(font
					(size 1.27 1.27)
					(thickness 0.15)
				)
				(justify left bottom)
				(hide yes)
			)
		)
		(property "Description" "FLASH - NOR Memory IC 32Mbit SPI - Quad I/O 133 MHz 8-SOIC"
			(at 92.71 231.14 0)
			(effects
				(font
					(size 1.27 1.27)
				)
				(hide yes)
			)
		)
		(property "MPN" "W25Q32JWSSIQ"
			(at 102.235 226.06 0)
			(effects
				(font
					(size 1.27 1.27)
					(thickness 0.15)
				)
			)
		)
		(property "Manufacturer" "Winbond"
			(at 125.73 247.65 0)
			(effects
				(font
					(size 1.27 1.27)
					(thickness 0.15)
				)
				(justify left bottom)
				(hide yes)
			)
		)
		(property "Author" "Antmicro"
			(at 125.73 250.19 0)
			(effects
				(font
					(size 1.27 1.27)
					(thickness 0.15)
				)
				(justify left bottom)
				(hide yes)
			)
		)
		(property "License" "Apache-2.0"
			(at 125.73 252.73 0)
			(effects
				(font
					(size 1.27 1.27)
					(thickness 0.15)
				)
				(justify left bottom)
				(hide yes)
			)
		)
		(pin "1"
		)
		(pin "2"
		)
		(pin "3"
		)
		(pin "4"
		)
		(pin "5"
		)
		(pin "6"
		)
		(pin "7"
		)
		(pin "8"
		)
		(instances
			(project "artix-dc-scm"
				(path ""
					(reference "U2")
					(unit 1)
				)
			)
		)
	)
	(symbol
		(lib_id "antmicroB2BConnectors:Plug_Molex_SlimStack_2x25_529910508")
		(at 233.68 171.45 180)
		(unit 1)
		(exclude_from_sim no)
		(in_bom yes)
		(on_board yes)
		(dnp no)
		(property "Reference" "J8"
			(at 227.965 103.505 0)
			(effects
				(font
					(size 1.27 1.27)
				)
			)
		)
		(property "Value" "Plug_Molex_SlimStack_2x25_529910508"
			(at 208.28 166.37 0)
			(effects
				(font
					(size 1.27 1.27)
					(thickness 0.15)
				)
				(justify left bottom)
				(hide yes)
			)
		)
		(property "Footprint" "antmicro-footprints:Conn_Plug_Molex_SlimStack_2x25_529910508"
			(at 208.28 163.83 0)
			(effects
				(font
					(size 1.27 1.27)
					(thickness 0.15)
				)
				(justify left bottom)
				(hide yes)
			)
		)
		(property "Datasheet" "https://www.molex.com/en-us/products/part-detail/529910508?display=pdf"
			(at 208.28 161.29 0)
			(effects
				(font
					(size 1.27 1.27)
					(thickness 0.15)
				)
				(justify left bottom)
				(hide yes)
			)
		)
		(property "Description" "Mezzanine Connector, Receptacle, 0.5mm, 2Rows, 50Contacts, Surface Mount, Phosphor Bronze"
			(at 233.68 171.45 0)
			(effects
				(font
					(size 1.27 1.27)
				)
				(hide yes)
			)
		)
		(property "MPN" "529910508"
			(at 227.965 106.045 0)
			(effects
				(font
					(size 1.27 1.27)
					(thickness 0.15)
				)
			)
		)
		(property "Manufacturer" "Molex"
			(at 208.28 158.75 0)
			(effects
				(font
					(size 1.27 1.27)
					(thickness 0.15)
				)
				(justify left bottom)
				(hide yes)
			)
		)
		(property "Author" "Antmicro"
			(at 208.28 153.67 0)
			(effects
				(font
					(size 1.27 1.27)
					(thickness 0.15)
				)
				(justify left bottom)
				(hide yes)
			)
		)
		(property "License" "Apache-2.0"
			(at 208.28 151.13 0)
			(effects
				(font
					(size 1.27 1.27)
					(thickness 0.15)
				)
				(justify left bottom)
				(hide yes)
			)
		)
		(property "Pitch " "0.5 mm"
			(at 208.28 156.21 0)
			(effects
				(font
					(size 1.27 1.27)
				)
				(justify left bottom)
				(hide yes)
			)
		)
		(pin "1"
		)
		(pin "10"
		)
		(pin "11"
		)
		(pin "12"
		)
		(pin "13"
		)
		(pin "14"
		)
		(pin "15"
		)
		(pin "16"
		)
		(pin "17"
		)
		(pin "18"
		)
		(pin "19"
		)
		(pin "2"
		)
		(pin "20"
		)
		(pin "21"
		)
		(pin "22"
		)
		(pin "23"
		)
		(pin "24"
		)
		(pin "25"
		)
		(pin "26"
		)
		(pin "27"
		)
		(pin "28"
		)
		(pin "29"
		)
		(pin "3"
		)
		(pin "30"
		)
		(pin "31"
		)
		(pin "32"
		)
		(pin "33"
		)
		(pin "34"
		)
		(pin "35"
		)
		(pin "36"
		)
		(pin "37"
		)
		(pin "38"
		)
		(pin "39"
		)
		(pin "4"
		)
		(pin "40"
		)
		(pin "41"
		)
		(pin "42"
		)
		(pin "43"
		)
		(pin "44"
		)
		(pin "45"
		)
		(pin "46"
		)
		(pin "47"
		)
		(pin "48"
		)
		(pin "49"
		)
		(pin "5"
		)
		(pin "50"
		)
		(pin "6"
		)
		(pin "7"
		)
		(pin "8"
		)
		(pin "9"
		)
		(instances
			(project "artix-dc-scm"
				(path ""
					(reference "J8")
					(unit 1)
				)
			)
		)
	)
	(symbol
		(lib_id "antmicroGenericPinSockets:PinSocket_2x6_P2.54mm_Drill1.02mm_PMOD")
		(at 312.42 128.27 0)
		(unit 1)
		(exclude_from_sim no)
		(in_bom yes)
		(on_board yes)
		(dnp no)
		(fields_autoplaced yes)
		(property "Reference" "J4"
			(at 317.5 121.92 0)
			(effects
				(font
					(size 1.27 1.27)
				)
			)
		)
		(property "Value" "PinSocket_2x6_P2.54mm_Drill1.02mm_PMOD"
			(at 317.5 124.46 0)
			(effects
				(font
					(size 1.27 1.27)
					(thickness 0.15)
				)
				(hide yes)
			)
		)
		(property "Footprint" "antmicro-footprints:PinSocket_2x6_P2.54mm_Drill1.02mm_PMOD"
			(at 337.82 138.43 0)
			(effects
				(font
					(size 1.27 1.27)
					(thickness 0.15)
				)
				(justify left bottom)
				(hide yes)
			)
		)
		(property "Datasheet" "https://cdn.harwin.com/pdfs/M20-783.pdf"
			(at 337.82 140.97 0)
			(effects
				(font
					(size 1.27 1.27)
					(thickness 0.15)
				)
				(justify left bottom)
				(hide yes)
			)
		)
		(property "Description" "PCB Receptacle, Board-to-Board, 2.54 mm, 2 Rows, 12 Contacts, Through Hole Mount, M20"
			(at 312.42 128.27 0)
			(effects
				(font
					(size 1.27 1.27)
				)
				(hide yes)
			)
		)
		(property "MPN" "M20-7830642"
			(at 317.5 124.46 0)
			(effects
				(font
					(size 1.27 1.27)
					(thickness 0.15)
				)
			)
		)
		(property "Manufacturer" "Harwin"
			(at 337.82 146.05 0)
			(effects
				(font
					(size 1.27 1.27)
					(thickness 0.15)
				)
				(justify left bottom)
				(hide yes)
			)
		)
		(property "Author" "Antmicro"
			(at 337.82 148.59 0)
			(effects
				(font
					(size 1.27 1.27)
					(thickness 0.15)
				)
				(justify left bottom)
				(hide yes)
			)
		)
		(property "License" "Apache-2.0"
			(at 337.82 151.13 0)
			(effects
				(font
					(size 1.27 1.27)
					(thickness 0.15)
				)
				(justify left bottom)
				(hide yes)
			)
		)
		(pin "1"
		)
		(pin "10"
		)
		(pin "11"
		)
		(pin "12"
		)
		(pin "2"
		)
		(pin "3"
		)
		(pin "4"
		)
		(pin "5"
		)
		(pin "6"
		)
		(pin "7"
		)
		(pin "8"
		)
		(pin "9"
		)
		(instances
			(project "artix-dc-scm"
				(path ""
					(reference "J4")
					(unit 1)
				)
			)
		)
	)
	(symbol
		(lib_id "antmicropower:GND")
		(at 220.98 172.72 0)
		(mirror y)
		(unit 1)
		(exclude_from_sim no)
		(in_bom yes)
		(on_board yes)
		(dnp no)
		(property "Reference" "#PWR0110"
			(at 220.98 179.07 0)
			(effects
				(font
					(size 1.27 1.27)
				)
				(hide yes)
			)
		)
		(property "Value" "GND"
			(at 220.98 176.53 0)
			(effects
				(font
					(size 1.27 1.27)
				)
			)
		)
		(property "Footprint" ""
			(at 220.98 172.72 0)
			(effects
				(font
					(size 1.27 1.27)
				)
				(hide yes)
			)
		)
		(property "Datasheet" ""
			(at 220.98 172.72 0)
			(effects
				(font
					(size 1.27 1.27)
				)
				(hide yes)
			)
		)
		(property "Description" ""
			(at 220.98 172.72 0)
			(effects
				(font
					(size 1.27 1.27)
				)
				(hide yes)
			)
		)
		(property "Author" "Antmicro"
			(at 212.09 180.34 0)
			(effects
				(font
					(size 1.27 1.27)
					(thickness 0.15)
				)
				(justify left bottom)
				(hide yes)
			)
		)
		(property "License" "Apache-2.0"
			(at 212.09 182.88 0)
			(effects
				(font
					(size 1.27 1.27)
					(thickness 0.15)
				)
				(justify left bottom)
				(hide yes)
			)
		)
		(pin "1"
		)
		(instances
			(project "artix-dc-scm"
				(path ""
					(reference "#PWR0110")
					(unit 1)
				)
			)
		)
	)
	(symbol
		(lib_id "antmicropower:GND")
		(at 113.03 118.11 0)
		(mirror y)
		(unit 1)
		(exclude_from_sim no)
		(in_bom yes)
		(on_board yes)
		(dnp no)
		(property "Reference" "#PWR0246"
			(at 113.03 124.46 0)
			(effects
				(font
					(size 1.27 1.27)
				)
				(hide yes)
			)
		)
		(property "Value" "GND"
			(at 113.03 121.92 0)
			(effects
				(font
					(size 1.27 1.27)
				)
			)
		)
		(property "Footprint" ""
			(at 113.03 118.11 0)
			(effects
				(font
					(size 1.27 1.27)
				)
				(hide yes)
			)
		)
		(property "Datasheet" ""
			(at 113.03 118.11 0)
			(effects
				(font
					(size 1.27 1.27)
				)
				(hide yes)
			)
		)
		(property "Description" ""
			(at 113.03 118.11 0)
			(effects
				(font
					(size 1.27 1.27)
				)
				(hide yes)
			)
		)
		(property "Author" "Antmicro"
			(at 104.14 125.73 0)
			(effects
				(font
					(size 1.27 1.27)
					(thickness 0.15)
				)
				(justify left bottom)
				(hide yes)
			)
		)
		(property "License" "Apache-2.0"
			(at 104.14 128.27 0)
			(effects
				(font
					(size 1.27 1.27)
					(thickness 0.15)
				)
				(justify left bottom)
				(hide yes)
			)
		)
		(pin "1"
		)
		(instances
			(project "artix-dc-scm"
				(path ""
					(reference "#PWR0246")
					(unit 1)
				)
			)
		)
	)
	(symbol
		(lib_id "antmicroMechanicalParts:Spacer_Drill3.7mm_H4mm_9774040151R")
		(at 220.98 185.42 0)
		(unit 1)
		(exclude_from_sim no)
		(in_bom yes)
		(on_board yes)
		(dnp no)
		(fields_autoplaced yes)
		(property "Reference" "H2"
			(at 229.87 184.15 0)
			(effects
				(font
					(size 1.27 1.27)
					(thickness 0.15)
				)
				(justify left)
			)
		)
		(property "Value" "Spacer_Drill3.7mm_H4mm_9774040151R"
			(at 229.87 186.69 0)
			(effects
				(font
					(size 1.27 1.27)
					(thickness 0.15)
				)
				(justify left)
			)
		)
		(property "Footprint" "antmicro-footprints:Spacer_Drill3.7mm_H4mm_9774040151R"
			(at 243.84 193.04 0)
			(effects
				(font
					(size 1.27 1.27)
					(thickness 0.15)
				)
				(justify left bottom)
				(hide yes)
			)
		)
		(property "Datasheet" "https://www.we-online.com/components/products/datasheet/9774040151R.pdf"
			(at 243.84 195.58 0)
			(effects
				(font
					(size 1.27 1.27)
					(thickness 0.15)
				)
				(justify left bottom)
				(hide yes)
			)
		)
		(property "Description" "Round Standoff Threaded M2.5x0.45 Steel 0.157\" (4.00mm)"
			(at 220.98 185.42 0)
			(effects
				(font
					(size 1.27 1.27)
				)
				(hide yes)
			)
		)
		(property "Manufacturer" "Würth Elektronik"
			(at 243.84 198.12 0)
			(effects
				(font
					(size 1.27 1.27)
					(thickness 0.15)
				)
				(justify left bottom)
				(hide yes)
			)
		)
		(property "MPN" "9774040151R"
			(at 243.84 200.66 0)
			(effects
				(font
					(size 1.27 1.27)
					(thickness 0.15)
				)
				(justify left bottom)
				(hide yes)
			)
		)
		(property "Author" "Antmicro"
			(at 243.84 203.2 0)
			(effects
				(font
					(size 1.27 1.27)
					(thickness 0.15)
				)
				(justify left bottom)
				(hide yes)
			)
		)
		(property "License" "Apache-2.0"
			(at 243.84 205.74 0)
			(effects
				(font
					(size 1.27 1.27)
					(thickness 0.15)
				)
				(justify left bottom)
				(hide yes)
			)
		)
		(pin "1"
		)
		(instances
			(project "artix-dc-scm"
				(path ""
					(reference "H2")
					(unit 1)
				)
			)
		)
	)
	(symbol
		(lib_id "antmicropower:GND")
		(at 113.03 245.11 0)
		(mirror y)
		(unit 1)
		(exclude_from_sim no)
		(in_bom yes)
		(on_board yes)
		(dnp no)
		(property "Reference" "#PWR0247"
			(at 113.03 251.46 0)
			(effects
				(font
					(size 1.27 1.27)
				)
				(hide yes)
			)
		)
		(property "Value" "GND"
			(at 113.03 248.92 0)
			(effects
				(font
					(size 1.27 1.27)
				)
			)
		)
		(property "Footprint" ""
			(at 113.03 245.11 0)
			(effects
				(font
					(size 1.27 1.27)
				)
				(hide yes)
			)
		)
		(property "Datasheet" ""
			(at 113.03 245.11 0)
			(effects
				(font
					(size 1.27 1.27)
				)
				(hide yes)
			)
		)
		(property "Description" ""
			(at 113.03 245.11 0)
			(effects
				(font
					(size 1.27 1.27)
				)
				(hide yes)
			)
		)
		(property "Author" "Antmicro"
			(at 104.14 252.73 0)
			(effects
				(font
					(size 1.27 1.27)
					(thickness 0.15)
				)
				(justify left bottom)
				(hide yes)
			)
		)
		(property "License" "Apache-2.0"
			(at 104.14 255.27 0)
			(effects
				(font
					(size 1.27 1.27)
					(thickness 0.15)
				)
				(justify left bottom)
				(hide yes)
			)
		)
		(pin "1"
		)
		(instances
			(project "artix-dc-scm"
				(path ""
					(reference "#PWR0247")
					(unit 1)
				)
			)
		)
	)
	(symbol
		(lib_id "antmicropower:GND")
		(at 113.03 194.31 0)
		(mirror y)
		(unit 1)
		(exclude_from_sim no)
		(in_bom yes)
		(on_board yes)
		(dnp no)
		(property "Reference" "#PWR0245"
			(at 113.03 200.66 0)
			(effects
				(font
					(size 1.27 1.27)
				)
				(hide yes)
			)
		)
		(property "Value" "GND"
			(at 113.03 198.12 0)
			(effects
				(font
					(size 1.27 1.27)
				)
			)
		)
		(property "Footprint" ""
			(at 113.03 194.31 0)
			(effects
				(font
					(size 1.27 1.27)
				)
				(hide yes)
			)
		)
		(property "Datasheet" ""
			(at 113.03 194.31 0)
			(effects
				(font
					(size 1.27 1.27)
				)
				(hide yes)
			)
		)
		(property "Description" ""
			(at 113.03 194.31 0)
			(effects
				(font
					(size 1.27 1.27)
				)
				(hide yes)
			)
		)
		(property "Author" "Antmicro"
			(at 104.14 201.93 0)
			(effects
				(font
					(size 1.27 1.27)
					(thickness 0.15)
				)
				(justify left bottom)
				(hide yes)
			)
		)
		(property "License" "Apache-2.0"
			(at 104.14 204.47 0)
			(effects
				(font
					(size 1.27 1.27)
					(thickness 0.15)
				)
				(justify left bottom)
				(hide yes)
			)
		)
		(pin "1"
		)
		(instances
			(project "artix-dc-scm"
				(path ""
					(reference "#PWR0245")
					(unit 1)
				)
			)
		)
	)
	(symbol
		(lib_id "antmicropower:GND")
		(at 113.03 73.66 0)
		(mirror y)
		(unit 1)
		(exclude_from_sim no)
		(in_bom yes)
		(on_board yes)
		(dnp no)
		(property "Reference" "#PWR0248"
			(at 113.03 80.01 0)
			(effects
				(font
					(size 1.27 1.27)
				)
				(hide yes)
			)
		)
		(property "Value" "GND"
			(at 113.03 77.47 0)
			(effects
				(font
					(size 1.27 1.27)
				)
			)
		)
		(property "Footprint" ""
			(at 113.03 73.66 0)
			(effects
				(font
					(size 1.27 1.27)
				)
				(hide yes)
			)
		)
		(property "Datasheet" ""
			(at 113.03 73.66 0)
			(effects
				(font
					(size 1.27 1.27)
				)
				(hide yes)
			)
		)
		(property "Description" ""
			(at 113.03 73.66 0)
			(effects
				(font
					(size 1.27 1.27)
				)
				(hide yes)
			)
		)
		(property "Author" "Antmicro"
			(at 104.14 81.28 0)
			(effects
				(font
					(size 1.27 1.27)
					(thickness 0.15)
				)
				(justify left bottom)
				(hide yes)
			)
		)
		(property "License" "Apache-2.0"
			(at 104.14 83.82 0)
			(effects
				(font
					(size 1.27 1.27)
					(thickness 0.15)
				)
				(justify left bottom)
				(hide yes)
			)
		)
		(pin "1"
		)
		(instances
			(project "artix-dc-scm"
				(path ""
					(reference "#PWR0248")
					(unit 1)
				)
			)
		)
	)
)
